FILE_TYPE = MACRO_DRAWING;
SET COLOR_WIRE YELLOW;
SET COLOR_PROP ORANGE;
SET COLOR_DOT WHITE;
SET COLOR_ARC YELLOW;
SET COLOR_BODY GREEN;
SET COLOR_NOTE PURPLE;
SET PROP_DISPLAY VALUE;
SET PAGE_NUMBER P19;
FORCEADD GENOA_SP5..10
(-4525 3625);
FORCEPROP 1 LAST LOCATION U25
J 0
(-5170 6456);
DISPLAY 0.489362 (-5170 6456);
PAINT SKYBLUE (-5170 6456);
FORCEPROP 0 LAST $SEC 10
J 0
(-5150 6500);
DISPLAY 0.680851 (-5150 6500);
PAINT MONO (-5150 6500);
DISPLAY INVISIBLE (-5150 6500);
FORCEPROP 0 LAST CDS_SEC 10
J 0
(-5175 6425);
DISPLAY 1.021277 (-5175 6425);
DISPLAY INVISIBLE (-5175 6425);
FORCEPROP 0 LASTPIN (-5325 3000) $PN BC16
J 2
(-5335 3010);
DISPLAY 0.489362 (-5335 3010);
PAINT MONO (-5335 3010);
FORCEPROP 0 LASTPIN (-5325 2950) $PN BD16
J 2
(-5335 2960);
DISPLAY 0.489362 (-5335 2960);
PAINT MONO (-5335 2960);
FORCEPROP 0 LASTPIN (-5325 1850) $PN BF16
J 2
(-5335 1860);
DISPLAY 0.489362 (-5335 1860);
PAINT MONO (-5335 1860);
FORCEPROP 0 LASTPIN (-5325 1800) $PN BG16
J 2
(-5335 1810);
DISPLAY 0.489362 (-5335 1810);
PAINT MONO (-5335 1810);
FORCEPROP 0 LASTPIN (-5325 2150) $PN AT18
J 2
(-5335 2160);
DISPLAY 0.489362 (-5335 2160);
PAINT MONO (-5335 2160);
FORCEPROP 0 LASTPIN (-5325 2050) $PN AU17
J 2
(-5335 2060);
DISPLAY 0.489362 (-5335 2060);
PAINT MONO (-5335 2060);
FORCEPROP 0 LASTPIN (-5325 2850) $PN AU16
J 2
(-5335 2860);
DISPLAY 0.489362 (-5335 2860);
PAINT MONO (-5335 2860);
FORCEPROP 0 LASTPIN (-5325 2800) $PN AV18
J 2
(-5335 2810);
DISPLAY 0.489362 (-5335 2810);
PAINT MONO (-5335 2810);
FORCEPROP 0 LASTPIN (-5325 2700) $PN BN17
J 2
(-5335 2710);
DISPLAY 0.489362 (-5335 2710);
PAINT MONO (-5335 2710);
FORCEPROP 0 LASTPIN (-5325 1700) $PN AV16
J 2
(-5335 1710);
DISPLAY 0.489362 (-5335 1710);
PAINT MONO (-5335 1710);
FORCEPROP 0 LASTPIN (-5325 1650) $PN AW17
J 2
(-5335 1660);
DISPLAY 0.489362 (-5335 1660);
PAINT MONO (-5335 1660);
FORCEPROP 0 LASTPIN (-5325 1550) $PN BP18
J 2
(-5335 1560);
DISPLAY 0.489362 (-5335 1560);
PAINT MONO (-5335 1560);
FORCEPROP 0 LASTPIN (-5325 3850) $PN AW16
J 2
(-5335 3860);
DISPLAY 0.489362 (-5335 3860);
PAINT MONO (-5335 3860);
FORCEPROP 0 LASTPIN (-5325 3800) $PN AY16
J 2
(-5335 3810);
DISPLAY 0.489362 (-5335 3810);
PAINT MONO (-5335 3810);
FORCEPROP 0 LASTPIN (-5325 3750) $PN AY18
J 2
(-5335 3760);
DISPLAY 0.489362 (-5335 3760);
PAINT MONO (-5335 3760);
FORCEPROP 0 LASTPIN (-5325 3700) $PN BA17
J 2
(-5335 3710);
DISPLAY 0.489362 (-5335 3710);
PAINT MONO (-5335 3710);
FORCEPROP 0 LASTPIN (-5325 3650) $PN BA16
J 2
(-5335 3660);
DISPLAY 0.489362 (-5335 3660);
PAINT MONO (-5335 3660);
FORCEPROP 0 LASTPIN (-5325 3600) $PN BB16
J 2
(-5335 3610);
DISPLAY 0.489362 (-5335 3610);
PAINT MONO (-5335 3610);
FORCEPROP 0 LASTPIN (-5325 3550) $PN BB18
J 2
(-5335 3560);
DISPLAY 0.489362 (-5335 3560);
PAINT MONO (-5335 3560);
FORCEPROP 0 LASTPIN (-3725 2400) $PN AJ16
J 0
(-3715 2410);
DISPLAY 0.489362 (-3715 2410);
PAINT MONO (-3715 2410);
FORCEPROP 0 LASTPIN (-3725 2350) $PN AK18
J 0
(-3715 2360);
DISPLAY 0.489362 (-3715 2360);
PAINT MONO (-3715 2360);
FORCEPROP 0 LASTPIN (-3725 2300) $PN AK16
J 0
(-3715 2310);
DISPLAY 0.489362 (-3715 2310);
PAINT MONO (-3715 2310);
FORCEPROP 0 LASTPIN (-3725 2250) $PN AL17
J 0
(-3715 2260);
DISPLAY 0.489362 (-3715 2260);
PAINT MONO (-3715 2260);
FORCEPROP 0 LASTPIN (-3725 2200) $PN AN16
J 0
(-3715 2210);
DISPLAY 0.489362 (-3715 2210);
PAINT MONO (-3715 2210);
FORCEPROP 0 LASTPIN (-3725 2150) $PN AP18
J 0
(-3715 2160);
DISPLAY 0.489362 (-3715 2160);
PAINT MONO (-3715 2160);
FORCEPROP 0 LASTPIN (-3725 2100) $PN AP16
J 0
(-3715 2110);
DISPLAY 0.489362 (-3715 2110);
PAINT MONO (-3715 2110);
FORCEPROP 0 LASTPIN (-3725 2050) $PN AR17
J 0
(-3715 2060);
DISPLAY 0.489362 (-3715 2060);
PAINT MONO (-3715 2060);
FORCEPROP 0 LASTPIN (-3725 6000) $PN E16
J 0
(-3715 6010);
DISPLAY 0.489362 (-3715 6010);
PAINT MONO (-3715 6010);
FORCEPROP 0 LASTPIN (-3725 5950) $PN F18
J 0
(-3715 5960);
DISPLAY 0.489362 (-3715 5960);
PAINT MONO (-3715 5960);
FORCEPROP 0 LASTPIN (-3725 5900) $PN F16
J 0
(-3715 5910);
DISPLAY 0.489362 (-3715 5910);
PAINT MONO (-3715 5910);
FORCEPROP 0 LASTPIN (-3725 5850) $PN G17
J 0
(-3715 5860);
DISPLAY 0.489362 (-3715 5860);
PAINT MONO (-3715 5860);
FORCEPROP 0 LASTPIN (-3725 5800) $PN J16
J 0
(-3715 5810);
DISPLAY 0.489362 (-3715 5810);
PAINT MONO (-3715 5810);
FORCEPROP 0 LASTPIN (-3725 5750) $PN K18
J 0
(-3715 5760);
DISPLAY 0.489362 (-3715 5760);
PAINT MONO (-3715 5760);
FORCEPROP 0 LASTPIN (-3725 5700) $PN K16
J 0
(-3715 5710);
DISPLAY 0.489362 (-3715 5710);
PAINT MONO (-3715 5710);
FORCEPROP 0 LASTPIN (-3725 5650) $PN L17
J 0
(-3715 5660);
DISPLAY 0.489362 (-3715 5660);
PAINT MONO (-3715 5660);
FORCEPROP 0 LASTPIN (-3725 5550) $PN L16
J 0
(-3715 5560);
DISPLAY 0.489362 (-3715 5560);
PAINT MONO (-3715 5560);
FORCEPROP 0 LASTPIN (-3725 5500) $PN M18
J 0
(-3715 5510);
DISPLAY 0.489362 (-3715 5510);
PAINT MONO (-3715 5510);
FORCEPROP 0 LASTPIN (-3725 5450) $PN M16
J 0
(-3715 5460);
DISPLAY 0.489362 (-3715 5460);
PAINT MONO (-3715 5460);
FORCEPROP 0 LASTPIN (-3725 5400) $PN N17
J 0
(-3715 5410);
DISPLAY 0.489362 (-3715 5410);
PAINT MONO (-3715 5410);
FORCEPROP 0 LASTPIN (-3725 5350) $PN R16
J 0
(-3715 5360);
DISPLAY 0.489362 (-3715 5360);
PAINT MONO (-3715 5360);
FORCEPROP 0 LASTPIN (-3725 5300) $PN T18
J 0
(-3715 5310);
DISPLAY 0.489362 (-3715 5310);
PAINT MONO (-3715 5310);
FORCEPROP 0 LASTPIN (-3725 5250) $PN T16
J 0
(-3715 5260);
DISPLAY 0.489362 (-3715 5260);
PAINT MONO (-3715 5260);
FORCEPROP 0 LASTPIN (-3725 5200) $PN U17
J 0
(-3715 5210);
DISPLAY 0.489362 (-3715 5210);
PAINT MONO (-3715 5210);
FORCEPROP 0 LASTPIN (-3725 5100) $PN U16
J 0
(-3715 5110);
DISPLAY 0.489362 (-3715 5110);
PAINT MONO (-3715 5110);
FORCEPROP 0 LASTPIN (-3725 5050) $PN V18
J 0
(-3715 5060);
DISPLAY 0.489362 (-3715 5060);
PAINT MONO (-3715 5060);
FORCEPROP 0 LASTPIN (-3725 5000) $PN V16
J 0
(-3715 5010);
DISPLAY 0.489362 (-3715 5010);
PAINT MONO (-3715 5010);
FORCEPROP 0 LASTPIN (-3725 4950) $PN W17
J 0
(-3715 4960);
DISPLAY 0.489362 (-3715 4960);
PAINT MONO (-3715 4960);
FORCEPROP 0 LASTPIN (-3725 4900) $PN AA16
J 0
(-3715 4910);
DISPLAY 0.489362 (-3715 4910);
PAINT MONO (-3715 4910);
FORCEPROP 0 LASTPIN (-3725 4850) $PN AB18
J 0
(-3715 4860);
DISPLAY 0.489362 (-3715 4860);
PAINT MONO (-3715 4860);
FORCEPROP 0 LASTPIN (-3725 4800) $PN AB16
J 0
(-3715 4810);
DISPLAY 0.489362 (-3715 4810);
PAINT MONO (-3715 4810);
FORCEPROP 0 LASTPIN (-3725 4750) $PN AC17
J 0
(-3715 4760);
DISPLAY 0.489362 (-3715 4760);
PAINT MONO (-3715 4760);
FORCEPROP 0 LASTPIN (-3725 4650) $PN AC16
J 0
(-3715 4660);
DISPLAY 0.489362 (-3715 4660);
PAINT MONO (-3715 4660);
FORCEPROP 0 LASTPIN (-3725 4600) $PN AD18
J 0
(-3715 4610);
DISPLAY 0.489362 (-3715 4610);
PAINT MONO (-3715 4610);
FORCEPROP 0 LASTPIN (-3725 4550) $PN AD16
J 0
(-3715 4560);
DISPLAY 0.489362 (-3715 4560);
PAINT MONO (-3715 4560);
FORCEPROP 0 LASTPIN (-3725 4500) $PN AE17
J 0
(-3715 4510);
DISPLAY 0.489362 (-3715 4510);
PAINT MONO (-3715 4510);
FORCEPROP 0 LASTPIN (-3725 4450) $PN AG16
J 0
(-3715 4460);
DISPLAY 0.489362 (-3715 4460);
PAINT MONO (-3715 4460);
FORCEPROP 0 LASTPIN (-3725 4400) $PN AH18
J 0
(-3715 4410);
DISPLAY 0.489362 (-3715 4410);
PAINT MONO (-3715 4410);
FORCEPROP 0 LASTPIN (-3725 4350) $PN AH16
J 0
(-3715 4360);
DISPLAY 0.489362 (-3715 4360);
PAINT MONO (-3715 4360);
FORCEPROP 0 LASTPIN (-3725 4300) $PN AJ17
J 0
(-3715 4310);
DISPLAY 0.489362 (-3715 4310);
PAINT MONO (-3715 4310);
FORCEPROP 0 LASTPIN (-5325 6000) $PN G16
J 2
(-5335 6010);
DISPLAY 0.489362 (-5335 6010);
PAINT MONO (-5335 6010);
FORCEPROP 0 LASTPIN (-5325 5900) $PN N16
J 2
(-5335 5910);
DISPLAY 0.489362 (-5335 5910);
PAINT MONO (-5335 5910);
FORCEPROP 0 LASTPIN (-5325 5800) $PN W16
J 2
(-5335 5810);
DISPLAY 0.489362 (-5335 5810);
PAINT MONO (-5335 5810);
FORCEPROP 0 LASTPIN (-5325 5700) $PN AE16
J 2
(-5335 5710);
DISPLAY 0.489362 (-5335 5710);
PAINT MONO (-5335 5710);
FORCEPROP 0 LASTPIN (-5325 5600) $PN AL16
J 2
(-5335 5610);
DISPLAY 0.489362 (-5335 5610);
PAINT MONO (-5335 5610);
FORCEPROP 0 LASTPIN (-5325 5500) $PN J17
J 2
(-5335 5510);
DISPLAY 0.489362 (-5335 5510);
PAINT MONO (-5335 5510);
FORCEPROP 0 LASTPIN (-5325 5400) $PN R17
J 2
(-5335 5410);
DISPLAY 0.489362 (-5335 5410);
PAINT MONO (-5335 5410);
FORCEPROP 0 LASTPIN (-5325 5300) $PN AA17
J 2
(-5335 5310);
DISPLAY 0.489362 (-5335 5310);
PAINT MONO (-5335 5310);
FORCEPROP 0 LASTPIN (-5325 5200) $PN AG17
J 2
(-5335 5210);
DISPLAY 0.489362 (-5335 5210);
PAINT MONO (-5335 5210);
FORCEPROP 0 LASTPIN (-5325 5100) $PN AN17
J 2
(-5335 5110);
DISPLAY 0.489362 (-5335 5110);
PAINT MONO (-5335 5110);
FORCEPROP 0 LASTPIN (-5325 5950) $PN H16
J 2
(-5335 5960);
DISPLAY 0.489362 (-5335 5960);
PAINT MONO (-5335 5960);
FORCEPROP 0 LASTPIN (-5325 5850) $PN P16
J 2
(-5335 5860);
DISPLAY 0.489362 (-5335 5860);
PAINT MONO (-5335 5860);
FORCEPROP 0 LASTPIN (-5325 5750) $PN Y16
J 2
(-5335 5760);
DISPLAY 0.489362 (-5335 5760);
PAINT MONO (-5335 5760);
FORCEPROP 0 LASTPIN (-5325 5650) $PN AF16
J 2
(-5335 5660);
DISPLAY 0.489362 (-5335 5660);
PAINT MONO (-5335 5660);
FORCEPROP 0 LASTPIN (-5325 5550) $PN AM16
J 2
(-5335 5560);
DISPLAY 0.489362 (-5335 5560);
PAINT MONO (-5335 5560);
FORCEPROP 0 LASTPIN (-5325 5450) $PN H18
J 2
(-5335 5460);
DISPLAY 0.489362 (-5335 5460);
PAINT MONO (-5335 5460);
FORCEPROP 0 LASTPIN (-5325 5350) $PN P18
J 2
(-5335 5360);
DISPLAY 0.489362 (-5335 5360);
PAINT MONO (-5335 5360);
FORCEPROP 0 LASTPIN (-5325 5250) $PN Y18
J 2
(-5335 5260);
DISPLAY 0.489362 (-5335 5260);
PAINT MONO (-5335 5260);
FORCEPROP 0 LASTPIN (-5325 5150) $PN AF18
J 2
(-5335 5160);
DISPLAY 0.489362 (-5335 5160);
PAINT MONO (-5335 5160);
FORCEPROP 0 LASTPIN (-5325 5050) $PN AM18
J 2
(-5335 5060);
DISPLAY 0.489362 (-5335 5060);
PAINT MONO (-5335 5060);
FORCEPROP 0 LASTPIN (-5325 2600) $PN BC17
J 2
(-5335 2610);
DISPLAY 0.489362 (-5335 2610);
PAINT MONO (-5335 2610);
FORCEPROP 0 LASTPIN (-5325 2500) $PN BM18
J 2
(-5335 2510);
DISPLAY 0.489362 (-5335 2510);
PAINT MONO (-5335 2510);
FORCEPROP 0 LASTPIN (-5325 2450) $PN BN16
J 2
(-5335 2460);
DISPLAY 0.489362 (-5335 2460);
PAINT MONO (-5335 2460);
FORCEPROP 0 LASTPIN (-5325 2350) $PN BP16
J 2
(-5335 2360);
DISPLAY 0.489362 (-5335 2360);
PAINT MONO (-5335 2360);
FORCEPROP 0 LASTPIN (-5325 1450) $PN BL16
J 2
(-5335 1460);
DISPLAY 0.489362 (-5335 1460);
PAINT MONO (-5335 1460);
FORCEPROP 0 LASTPIN (-5325 1400) $PN BM16
J 2
(-5335 1410);
DISPLAY 0.489362 (-5335 1410);
PAINT MONO (-5335 1410);
FORCEPROP 0 LASTPIN (-5325 1300) $PN BR16
J 2
(-5335 1310);
DISPLAY 0.489362 (-5335 1310);
PAINT MONO (-5335 1310);
FORCEPROP 0 LASTPIN (-5325 3450) $PN BG17
J 2
(-5335 3460);
DISPLAY 0.489362 (-5335 3460);
PAINT MONO (-5335 3460);
FORCEPROP 0 LASTPIN (-5325 3400) $PN BH18
J 2
(-5335 3410);
DISPLAY 0.489362 (-5335 3410);
PAINT MONO (-5335 3410);
FORCEPROP 0 LASTPIN (-5325 3350) $PN BH16
J 2
(-5335 3360);
DISPLAY 0.489362 (-5335 3360);
PAINT MONO (-5335 3360);
FORCEPROP 0 LASTPIN (-5325 3300) $PN BJ16
J 2
(-5335 3310);
DISPLAY 0.489362 (-5335 3310);
PAINT MONO (-5335 3310);
FORCEPROP 0 LASTPIN (-5325 3250) $PN BJ17
J 2
(-5335 3260);
DISPLAY 0.489362 (-5335 3260);
PAINT MONO (-5335 3260);
FORCEPROP 0 LASTPIN (-5325 3200) $PN BK18
J 2
(-5335 3210);
DISPLAY 0.489362 (-5335 3210);
PAINT MONO (-5335 3210);
FORCEPROP 0 LASTPIN (-5325 3150) $PN BK16
J 2
(-5335 3160);
DISPLAY 0.489362 (-5335 3160);
PAINT MONO (-5335 3160);
FORCEPROP 0 LASTPIN (-3725 1950) $PN BY16
J 0
(-3715 1960);
DISPLAY 0.489362 (-3715 1960);
PAINT MONO (-3715 1960);
FORCEPROP 0 LASTPIN (-3725 1900) $PN CA17
J 0
(-3715 1910);
DISPLAY 0.489362 (-3715 1910);
PAINT MONO (-3715 1910);
FORCEPROP 0 LASTPIN (-3725 1850) $PN CA16
J 0
(-3715 1860);
DISPLAY 0.489362 (-3715 1860);
PAINT MONO (-3715 1860);
FORCEPROP 0 LASTPIN (-3725 1800) $PN CB18
J 0
(-3715 1810);
DISPLAY 0.489362 (-3715 1810);
PAINT MONO (-3715 1810);
FORCEPROP 0 LASTPIN (-3725 1750) $PN BT16
J 0
(-3715 1760);
DISPLAY 0.489362 (-3715 1760);
PAINT MONO (-3715 1760);
FORCEPROP 0 LASTPIN (-3725 1700) $PN BU17
J 0
(-3715 1710);
DISPLAY 0.489362 (-3715 1710);
PAINT MONO (-3715 1710);
FORCEPROP 0 LASTPIN (-3725 1650) $PN BU16
J 0
(-3715 1660);
DISPLAY 0.489362 (-3715 1660);
PAINT MONO (-3715 1660);
FORCEPROP 0 LASTPIN (-3725 1600) $PN BV18
J 0
(-3715 1610);
DISPLAY 0.489362 (-3715 1610);
PAINT MONO (-3715 1610);
FORCEPROP 0 LASTPIN (-3725 4200) $PN CB16
J 0
(-3715 4210);
DISPLAY 0.489362 (-3715 4210);
PAINT MONO (-3715 4210);
FORCEPROP 0 LASTPIN (-3725 4150) $PN CC17
J 0
(-3715 4160);
DISPLAY 0.489362 (-3715 4160);
PAINT MONO (-3715 4160);
FORCEPROP 0 LASTPIN (-3725 4100) $PN CC16
J 0
(-3715 4110);
DISPLAY 0.489362 (-3715 4110);
PAINT MONO (-3715 4110);
FORCEPROP 0 LASTPIN (-3725 4050) $PN CD18
J 0
(-3715 4060);
DISPLAY 0.489362 (-3715 4060);
PAINT MONO (-3715 4060);
FORCEPROP 0 LASTPIN (-3725 4000) $PN CF16
J 0
(-3715 4010);
DISPLAY 0.489362 (-3715 4010);
PAINT MONO (-3715 4010);
FORCEPROP 0 LASTPIN (-3725 3950) $PN CG17
J 0
(-3715 3960);
DISPLAY 0.489362 (-3715 3960);
PAINT MONO (-3715 3960);
FORCEPROP 0 LASTPIN (-3725 3900) $PN CG16
J 0
(-3715 3910);
DISPLAY 0.489362 (-3715 3910);
PAINT MONO (-3715 3910);
FORCEPROP 0 LASTPIN (-3725 3850) $PN CH18
J 0
(-3715 3860);
DISPLAY 0.489362 (-3715 3860);
PAINT MONO (-3715 3860);
FORCEPROP 0 LASTPIN (-3725 3750) $PN CH16
J 0
(-3715 3760);
DISPLAY 0.489362 (-3715 3760);
PAINT MONO (-3715 3760);
FORCEPROP 0 LASTPIN (-3725 3700) $PN CJ17
J 0
(-3715 3710);
DISPLAY 0.489362 (-3715 3710);
PAINT MONO (-3715 3710);
FORCEPROP 0 LASTPIN (-3725 3650) $PN CJ16
J 0
(-3715 3660);
DISPLAY 0.489362 (-3715 3660);
PAINT MONO (-3715 3660);
FORCEPROP 0 LASTPIN (-3725 3600) $PN CK18
J 0
(-3715 3610);
DISPLAY 0.489362 (-3715 3610);
PAINT MONO (-3715 3610);
FORCEPROP 0 LASTPIN (-3725 3550) $PN CM16
J 0
(-3715 3560);
DISPLAY 0.489362 (-3715 3560);
PAINT MONO (-3715 3560);
FORCEPROP 0 LASTPIN (-3725 3500) $PN CN17
J 0
(-3715 3510);
DISPLAY 0.489362 (-3715 3510);
PAINT MONO (-3715 3510);
FORCEPROP 0 LASTPIN (-3725 3450) $PN CN16
J 0
(-3715 3460);
DISPLAY 0.489362 (-3715 3460);
PAINT MONO (-3715 3460);
FORCEPROP 0 LASTPIN (-3725 3400) $PN CP18
J 0
(-3715 3410);
DISPLAY 0.489362 (-3715 3410);
PAINT MONO (-3715 3410);
FORCEPROP 0 LASTPIN (-3725 3300) $PN CP16
J 0
(-3715 3310);
DISPLAY 0.489362 (-3715 3310);
PAINT MONO (-3715 3310);
FORCEPROP 0 LASTPIN (-3725 3250) $PN CR17
J 0
(-3715 3260);
DISPLAY 0.489362 (-3715 3260);
PAINT MONO (-3715 3260);
FORCEPROP 0 LASTPIN (-3725 3200) $PN CR16
J 0
(-3715 3210);
DISPLAY 0.489362 (-3715 3210);
PAINT MONO (-3715 3210);
FORCEPROP 0 LASTPIN (-3725 3150) $PN CT18
J 0
(-3715 3160);
DISPLAY 0.489362 (-3715 3160);
PAINT MONO (-3715 3160);
FORCEPROP 0 LASTPIN (-3725 3100) $PN CV16
J 0
(-3715 3110);
DISPLAY 0.489362 (-3715 3110);
PAINT MONO (-3715 3110);
FORCEPROP 0 LASTPIN (-3725 3050) $PN CW17
J 0
(-3715 3060);
DISPLAY 0.489362 (-3715 3060);
PAINT MONO (-3715 3060);
FORCEPROP 0 LASTPIN (-3725 3000) $PN CW16
J 0
(-3715 3010);
DISPLAY 0.489362 (-3715 3010);
PAINT MONO (-3715 3010);
FORCEPROP 0 LASTPIN (-3725 2950) $PN CY18
J 0
(-3715 2960);
DISPLAY 0.489362 (-3715 2960);
PAINT MONO (-3715 2960);
FORCEPROP 0 LASTPIN (-3725 2850) $PN CY16
J 0
(-3715 2860);
DISPLAY 0.489362 (-3715 2860);
PAINT MONO (-3715 2860);
FORCEPROP 0 LASTPIN (-3725 2800) $PN DA17
J 0
(-3715 2810);
DISPLAY 0.489362 (-3715 2810);
PAINT MONO (-3715 2810);
FORCEPROP 0 LASTPIN (-3725 2750) $PN DA16
J 0
(-3715 2760);
DISPLAY 0.489362 (-3715 2760);
PAINT MONO (-3715 2760);
FORCEPROP 0 LASTPIN (-3725 2700) $PN DB18
J 0
(-3715 2710);
DISPLAY 0.489362 (-3715 2710);
PAINT MONO (-3715 2710);
FORCEPROP 0 LASTPIN (-3725 2650) $PN DD16
J 0
(-3715 2660);
DISPLAY 0.489362 (-3715 2660);
PAINT MONO (-3715 2660);
FORCEPROP 0 LASTPIN (-3725 2600) $PN DE17
J 0
(-3715 2610);
DISPLAY 0.489362 (-3715 2610);
PAINT MONO (-3715 2610);
FORCEPROP 0 LASTPIN (-3725 2550) $PN DE16
J 0
(-3715 2560);
DISPLAY 0.489362 (-3715 2560);
PAINT MONO (-3715 2560);
FORCEPROP 0 LASTPIN (-3725 2500) $PN DF16
J 0
(-3715 2510);
DISPLAY 0.489362 (-3715 2510);
PAINT MONO (-3715 2510);
FORCEPROP 0 LASTPIN (-5325 4950) $PN CD16
J 2
(-5335 4960);
DISPLAY 0.489362 (-5335 4960);
PAINT MONO (-5335 4960);
FORCEPROP 0 LASTPIN (-5325 4850) $PN CK16
J 2
(-5335 4860);
DISPLAY 0.489362 (-5335 4860);
PAINT MONO (-5335 4860);
FORCEPROP 0 LASTPIN (-5325 4750) $PN CT16
J 2
(-5335 4760);
DISPLAY 0.489362 (-5335 4760);
PAINT MONO (-5335 4760);
FORCEPROP 0 LASTPIN (-5325 4650) $PN DB16
J 2
(-5335 4660);
DISPLAY 0.489362 (-5335 4660);
PAINT MONO (-5335 4660);
FORCEPROP 0 LASTPIN (-5325 4550) $PN BY18
J 2
(-5335 4560);
DISPLAY 0.489362 (-5335 4560);
PAINT MONO (-5335 4560);
FORCEPROP 0 LASTPIN (-5325 4450) $PN CF18
J 2
(-5335 4460);
DISPLAY 0.489362 (-5335 4460);
PAINT MONO (-5335 4460);
FORCEPROP 0 LASTPIN (-5325 4350) $PN CM18
J 2
(-5335 4360);
DISPLAY 0.489362 (-5335 4360);
PAINT MONO (-5335 4360);
FORCEPROP 0 LASTPIN (-5325 4250) $PN CV18
J 2
(-5335 4260);
DISPLAY 0.489362 (-5335 4260);
PAINT MONO (-5335 4260);
FORCEPROP 0 LASTPIN (-5325 4150) $PN DD18
J 2
(-5335 4160);
DISPLAY 0.489362 (-5335 4160);
PAINT MONO (-5335 4160);
FORCEPROP 0 LASTPIN (-5325 4050) $PN BV16
J 2
(-5335 4060);
DISPLAY 0.489362 (-5335 4060);
PAINT MONO (-5335 4060);
FORCEPROP 0 LASTPIN (-5325 4900) $PN CE16
J 2
(-5335 4910);
DISPLAY 0.489362 (-5335 4910);
PAINT MONO (-5335 4910);
FORCEPROP 0 LASTPIN (-5325 4800) $PN CL16
J 2
(-5335 4810);
DISPLAY 0.489362 (-5335 4810);
PAINT MONO (-5335 4810);
FORCEPROP 0 LASTPIN (-5325 4700) $PN CU16
J 2
(-5335 4710);
DISPLAY 0.489362 (-5335 4710);
PAINT MONO (-5335 4710);
FORCEPROP 0 LASTPIN (-5325 4600) $PN DC16
J 2
(-5335 4610);
DISPLAY 0.489362 (-5335 4610);
PAINT MONO (-5335 4610);
FORCEPROP 0 LASTPIN (-5325 4500) $PN BW17
J 2
(-5335 4510);
DISPLAY 0.489362 (-5335 4510);
PAINT MONO (-5335 4510);
FORCEPROP 0 LASTPIN (-5325 4400) $PN CE17
J 2
(-5335 4410);
DISPLAY 0.489362 (-5335 4410);
PAINT MONO (-5335 4410);
FORCEPROP 0 LASTPIN (-5325 4300) $PN CL17
J 2
(-5335 4310);
DISPLAY 0.489362 (-5335 4310);
PAINT MONO (-5335 4310);
FORCEPROP 0 LASTPIN (-5325 4200) $PN CU17
J 2
(-5335 4210);
DISPLAY 0.489362 (-5335 4210);
PAINT MONO (-5335 4210);
FORCEPROP 0 LASTPIN (-5325 4100) $PN DC17
J 2
(-5335 4110);
DISPLAY 0.489362 (-5335 4110);
PAINT MONO (-5335 4110);
FORCEPROP 0 LASTPIN (-5325 4000) $PN BW16
J 2
(-5335 4010);
DISPLAY 0.489362 (-5335 4010);
PAINT MONO (-5335 4010);
FORCEPROP 0 LASTPIN (-5325 2250) $PN BL17
J 2
(-5335 2260);
DISPLAY 0.489362 (-5335 2260);
PAINT MONO (-5335 2260);
FORCEPROP 0 LASTPIN (-5325 1200) $PN BF18
J 2
(-5335 1210);
DISPLAY 0.489362 (-5335 1210);
PAINT MONO (-5335 1210);
FORCEPROP 2 LAST PART_TYPE SMLF
J 0
(-5175 6375);
DISPLAY 1.021277 (-5175 6375);
FORCEPROP 1 LAST MATERIAL IO
J 0
(-5170 6182);
DISPLAY 0.489362 (-5170 6182);
PAINT SKYBLUE (-5170 6182);
FORCEPROP 2 LAST VALUE SOCKET6096_13568-001
J 0
(-5175 6275);
DISPLAY 0.489362 (-5175 6275);
PAINT SKYBLUE (-5175 6275);
FORCEPROP 1 LAST PART_NUMBER DGA^6000030
J 0
(-5170 6309);
DISPLAY 0.489362 (-5170 6309);
PAINT SKYBLUE (-5170 6309);
FORCEPROP 2 LAST CDS_LIB pure_quanta
J 0
(-4525 3625);
DISPLAY INVISIBLE (-4525 3625);
FORCEPROP 1 LAST CDS_LMAN_SYM_OUTLINE -650,2525,650,-2525
J 0
(-4525 3625);
DISPLAY 0.468085 (-4525 3625);
PAINT GREEN (-4525 3625);
DISPLAY INVISIBLE (-4525 3625);
FORCEPROP 1 LAST NEEDS_NO_SIZE TRUE
J 0
(-4525 3625);
DISPLAY 0.723404 (-4525 3625);
PAINT GREEN (-4525 3625);
DISPLAY INVISIBLE (-4525 3625);
FORCEPROP 1 LAST PATH I159
J 0
(-4525 3625);
DISPLAY 0.723404 (-4525 3625);
PAINT GREEN (-4525 3625);
DISPLAY INVISIBLE (-4525 3625);
FORCEADD OFFPAGE..3
(-2525 6025);
FORCEPROP 2 LAST $XR0 94 
J 0
(-2311 6025);
DISPLAY 0.638298 (-2311 6025);
PAINT MONO (-2311 6025);
FORCEPROP 2 LAST PATH I160
J 0
(-2300 6075);
DISPLAY 1.021277 (-2300 6075);
DISPLAY INVISIBLE (-2300 6075);
FORCEPROP 1 LAST COMMENT_BODY TRUE
J 0
(-2575 5925);
DISPLAY 0.872340 (-2575 5925);
PAINT GREEN (-2575 5925);
DISPLAY INVISIBLE (-2575 5925);
FORCEPROP 1 LAST OFFPAGE TRUE
J 0
(-2200 5900);
DISPLAY 0.872340 (-2200 5900);
PAINT GREEN (-2200 5900);
DISPLAY INVISIBLE (-2200 5900);
FORCEPROP 2 LAST CDS_LIB mstr_standard
J 0
(-2525 6025);
DISPLAY 0.723404 (-2525 6025);
PAINT MONO (-2525 6025);
DISPLAY INVISIBLE (-2525 6025);
FORCEADD OFFPAGE..3
(-2525 4225);
FORCEPROP 2 LAST $XR0 94 
J 0
(-2311 4225);
DISPLAY 0.638298 (-2311 4225);
PAINT MONO (-2311 4225);
FORCEPROP 2 LAST PATH I161
J 0
(-2300 4275);
DISPLAY 1.021277 (-2300 4275);
DISPLAY INVISIBLE (-2300 4275);
FORCEPROP 1 LAST COMMENT_BODY TRUE
J 0
(-2575 4125);
DISPLAY 0.872340 (-2575 4125);
PAINT GREEN (-2575 4125);
DISPLAY INVISIBLE (-2575 4125);
FORCEPROP 1 LAST OFFPAGE TRUE
J 0
(-2200 4100);
DISPLAY 0.872340 (-2200 4100);
PAINT GREEN (-2200 4100);
DISPLAY INVISIBLE (-2200 4100);
FORCEPROP 2 LAST CDS_LIB mstr_standard
J 0
(-2525 4225);
DISPLAY 0.723404 (-2525 4225);
PAINT MONO (-2525 4225);
DISPLAY INVISIBLE (-2525 4225);
FORCEADD TAP..1
(-3250 5900);
FORCEPROP 3 LASTPIN (-3300 5900) SIG_NAME M_J_CPU0_SA_DQ<2>
J 0
(-3290 5910);
DISPLAY 0.659574 (-3290 5910);
PAINT MONO (-3290 5910);
DISPLAY INVISIBLE (-3290 5910);
FORCEPROP 1 LASTPIN (-3300 5900) BN 2
J 0
(-3312 5908);
DISPLAY 0.489362 (-3312 5908);
PAINT GREEN (-3312 5908);
FORCEPROP 2 LAST CDS_LIB mstr_standard
J 0
(-3250 5900);
DISPLAY 0.723404 (-3250 5900);
PAINT MONO (-3250 5900);
DISPLAY INVISIBLE (-3250 5900);
FORCEPROP 1 LAST BODY_TYPE PLUMBING
J 0
(-3250 5950);
DISPLAY 0.872340 (-3250 5950);
PAINT GREEN (-3250 5950);
DISPLAY INVISIBLE (-3250 5950);
FORCEPROP 1 LAST HDL_TAP TRUE
J 0
(-2925 5775);
DISPLAY 0.872340 (-2925 5775);
DISPLAY INVISIBLE (-2925 5775);
FORCEPROP 1 LAST PATH I162
J 0
(-3252 5900);
DISPLAY 0.872340 (-3252 5900);
PAINT GREEN (-3252 5900);
DISPLAY INVISIBLE (-3252 5900);
FORCEADD TAP..1
(-3250 6000);
FORCEPROP 3 LASTPIN (-3300 6000) SIG_NAME M_J_CPU0_SA_DQ<0>
J 0
(-3290 6010);
DISPLAY 0.659574 (-3290 6010);
PAINT MONO (-3290 6010);
DISPLAY INVISIBLE (-3290 6010);
FORCEPROP 1 LASTPIN (-3300 6000) BN 0
J 0
(-3312 6008);
DISPLAY 0.489362 (-3312 6008);
PAINT GREEN (-3312 6008);
FORCEPROP 2 LAST CDS_LIB mstr_standard
J 0
(-3250 6000);
DISPLAY 0.723404 (-3250 6000);
PAINT MONO (-3250 6000);
DISPLAY INVISIBLE (-3250 6000);
FORCEPROP 1 LAST BODY_TYPE PLUMBING
J 0
(-3250 6050);
DISPLAY 0.872340 (-3250 6050);
PAINT GREEN (-3250 6050);
DISPLAY INVISIBLE (-3250 6050);
FORCEPROP 1 LAST HDL_TAP TRUE
J 0
(-2925 5875);
DISPLAY 0.872340 (-2925 5875);
DISPLAY INVISIBLE (-2925 5875);
FORCEPROP 1 LAST PATH I163
J 0
(-3252 6000);
DISPLAY 0.872340 (-3252 6000);
PAINT GREEN (-3252 6000);
DISPLAY INVISIBLE (-3252 6000);
FORCEADD TAP..1
(-3250 5950);
FORCEPROP 3 LASTPIN (-3300 5950) SIG_NAME M_J_CPU0_SA_DQ<1>
J 0
(-3290 5960);
DISPLAY 0.659574 (-3290 5960);
PAINT MONO (-3290 5960);
DISPLAY INVISIBLE (-3290 5960);
FORCEPROP 1 LASTPIN (-3300 5950) BN 1
J 0
(-3312 5958);
DISPLAY 0.489362 (-3312 5958);
PAINT GREEN (-3312 5958);
FORCEPROP 2 LAST CDS_LIB mstr_standard
J 0
(-3250 5950);
DISPLAY 0.723404 (-3250 5950);
PAINT MONO (-3250 5950);
DISPLAY INVISIBLE (-3250 5950);
FORCEPROP 1 LAST BODY_TYPE PLUMBING
J 0
(-3250 6000);
DISPLAY 0.872340 (-3250 6000);
PAINT GREEN (-3250 6000);
DISPLAY INVISIBLE (-3250 6000);
FORCEPROP 1 LAST HDL_TAP TRUE
J 0
(-2925 5825);
DISPLAY 0.872340 (-2925 5825);
DISPLAY INVISIBLE (-2925 5825);
FORCEPROP 1 LAST PATH I164
J 0
(-3252 5950);
DISPLAY 0.872340 (-3252 5950);
PAINT GREEN (-3252 5950);
DISPLAY INVISIBLE (-3252 5950);
FORCEADD TAP..1
(-3250 5850);
FORCEPROP 3 LASTPIN (-3300 5850) SIG_NAME M_J_CPU0_SA_DQ<3>
J 0
(-3290 5860);
DISPLAY 0.659574 (-3290 5860);
PAINT MONO (-3290 5860);
DISPLAY INVISIBLE (-3290 5860);
FORCEPROP 1 LASTPIN (-3300 5850) BN 3
J 0
(-3312 5858);
DISPLAY 0.489362 (-3312 5858);
PAINT GREEN (-3312 5858);
FORCEPROP 2 LAST CDS_LIB mstr_standard
J 0
(-3250 5850);
DISPLAY 0.723404 (-3250 5850);
PAINT MONO (-3250 5850);
DISPLAY INVISIBLE (-3250 5850);
FORCEPROP 1 LAST BODY_TYPE PLUMBING
J 0
(-3250 5900);
DISPLAY 0.872340 (-3250 5900);
PAINT GREEN (-3250 5900);
DISPLAY INVISIBLE (-3250 5900);
FORCEPROP 1 LAST HDL_TAP TRUE
J 0
(-2925 5725);
DISPLAY 0.872340 (-2925 5725);
DISPLAY INVISIBLE (-2925 5725);
FORCEPROP 1 LAST PATH I165
J 0
(-3252 5850);
DISPLAY 0.872340 (-3252 5850);
PAINT GREEN (-3252 5850);
DISPLAY INVISIBLE (-3252 5850);
FORCEADD TAP..1
(-3250 5800);
FORCEPROP 3 LASTPIN (-3300 5800) SIG_NAME M_J_CPU0_SA_DQ<4>
J 0
(-3290 5810);
DISPLAY 0.659574 (-3290 5810);
PAINT MONO (-3290 5810);
DISPLAY INVISIBLE (-3290 5810);
FORCEPROP 1 LASTPIN (-3300 5800) BN 4
J 0
(-3312 5808);
DISPLAY 0.489362 (-3312 5808);
PAINT GREEN (-3312 5808);
FORCEPROP 2 LAST CDS_LIB mstr_standard
J 0
(-3250 5800);
DISPLAY 0.723404 (-3250 5800);
PAINT MONO (-3250 5800);
DISPLAY INVISIBLE (-3250 5800);
FORCEPROP 1 LAST BODY_TYPE PLUMBING
J 0
(-3250 5850);
DISPLAY 0.872340 (-3250 5850);
PAINT GREEN (-3250 5850);
DISPLAY INVISIBLE (-3250 5850);
FORCEPROP 1 LAST HDL_TAP TRUE
J 0
(-2925 5675);
DISPLAY 0.872340 (-2925 5675);
DISPLAY INVISIBLE (-2925 5675);
FORCEPROP 1 LAST PATH I166
J 0
(-3252 5800);
DISPLAY 0.872340 (-3252 5800);
PAINT GREEN (-3252 5800);
DISPLAY INVISIBLE (-3252 5800);
FORCEADD TAP..1
(-3250 5700);
FORCEPROP 3 LASTPIN (-3300 5700) SIG_NAME M_J_CPU0_SA_DQ<6>
J 0
(-3290 5710);
DISPLAY 0.659574 (-3290 5710);
PAINT MONO (-3290 5710);
DISPLAY INVISIBLE (-3290 5710);
FORCEPROP 1 LASTPIN (-3300 5700) BN 6
J 0
(-3312 5708);
DISPLAY 0.489362 (-3312 5708);
PAINT GREEN (-3312 5708);
FORCEPROP 2 LAST CDS_LIB mstr_standard
J 0
(-3250 5700);
DISPLAY 0.723404 (-3250 5700);
PAINT MONO (-3250 5700);
DISPLAY INVISIBLE (-3250 5700);
FORCEPROP 1 LAST BODY_TYPE PLUMBING
J 0
(-3250 5750);
DISPLAY 0.872340 (-3250 5750);
PAINT GREEN (-3250 5750);
DISPLAY INVISIBLE (-3250 5750);
FORCEPROP 1 LAST HDL_TAP TRUE
J 0
(-2925 5575);
DISPLAY 0.872340 (-2925 5575);
DISPLAY INVISIBLE (-2925 5575);
FORCEPROP 1 LAST PATH I167
J 0
(-3252 5700);
DISPLAY 0.872340 (-3252 5700);
PAINT GREEN (-3252 5700);
DISPLAY INVISIBLE (-3252 5700);
FORCEADD TAP..1
(-3250 5750);
FORCEPROP 3 LASTPIN (-3300 5750) SIG_NAME M_J_CPU0_SA_DQ<5>
J 0
(-3290 5760);
DISPLAY 0.659574 (-3290 5760);
PAINT MONO (-3290 5760);
DISPLAY INVISIBLE (-3290 5760);
FORCEPROP 1 LASTPIN (-3300 5750) BN 5
J 0
(-3312 5758);
DISPLAY 0.489362 (-3312 5758);
PAINT GREEN (-3312 5758);
FORCEPROP 2 LAST CDS_LIB mstr_standard
J 0
(-3250 5750);
DISPLAY 0.723404 (-3250 5750);
PAINT MONO (-3250 5750);
DISPLAY INVISIBLE (-3250 5750);
FORCEPROP 1 LAST BODY_TYPE PLUMBING
J 0
(-3250 5800);
DISPLAY 0.872340 (-3250 5800);
PAINT GREEN (-3250 5800);
DISPLAY INVISIBLE (-3250 5800);
FORCEPROP 1 LAST HDL_TAP TRUE
J 0
(-2925 5625);
DISPLAY 0.872340 (-2925 5625);
DISPLAY INVISIBLE (-2925 5625);
FORCEPROP 1 LAST PATH I168
J 0
(-3252 5750);
DISPLAY 0.872340 (-3252 5750);
PAINT GREEN (-3252 5750);
DISPLAY INVISIBLE (-3252 5750);
FORCEADD TAP..1
(-3250 5650);
FORCEPROP 3 LASTPIN (-3300 5650) SIG_NAME M_J_CPU0_SA_DQ<7>
J 0
(-3290 5660);
DISPLAY 0.659574 (-3290 5660);
PAINT MONO (-3290 5660);
DISPLAY INVISIBLE (-3290 5660);
FORCEPROP 1 LASTPIN (-3300 5650) BN 7
J 0
(-3312 5658);
DISPLAY 0.489362 (-3312 5658);
PAINT GREEN (-3312 5658);
FORCEPROP 2 LAST CDS_LIB mstr_standard
J 0
(-3250 5650);
DISPLAY 0.723404 (-3250 5650);
PAINT MONO (-3250 5650);
DISPLAY INVISIBLE (-3250 5650);
FORCEPROP 1 LAST BODY_TYPE PLUMBING
J 0
(-3250 5700);
DISPLAY 0.872340 (-3250 5700);
PAINT GREEN (-3250 5700);
DISPLAY INVISIBLE (-3250 5700);
FORCEPROP 1 LAST HDL_TAP TRUE
J 0
(-2925 5525);
DISPLAY 0.872340 (-2925 5525);
DISPLAY INVISIBLE (-2925 5525);
FORCEPROP 1 LAST PATH I169
J 0
(-3252 5650);
DISPLAY 0.872340 (-3252 5650);
PAINT GREEN (-3252 5650);
DISPLAY INVISIBLE (-3252 5650);
FORCEADD TAP..1
(-3250 5550);
FORCEPROP 3 LASTPIN (-3300 5550) SIG_NAME M_J_CPU0_SA_DQ<8>
J 0
(-3290 5560);
DISPLAY 0.659574 (-3290 5560);
PAINT MONO (-3290 5560);
DISPLAY INVISIBLE (-3290 5560);
FORCEPROP 1 LASTPIN (-3300 5550) BN 8
J 0
(-3312 5558);
DISPLAY 0.489362 (-3312 5558);
PAINT GREEN (-3312 5558);
FORCEPROP 2 LAST CDS_LIB mstr_standard
J 0
(-3250 5550);
DISPLAY 0.723404 (-3250 5550);
PAINT MONO (-3250 5550);
DISPLAY INVISIBLE (-3250 5550);
FORCEPROP 1 LAST BODY_TYPE PLUMBING
J 0
(-3250 5600);
DISPLAY 0.872340 (-3250 5600);
PAINT GREEN (-3250 5600);
DISPLAY INVISIBLE (-3250 5600);
FORCEPROP 1 LAST HDL_TAP TRUE
J 0
(-2925 5425);
DISPLAY 0.872340 (-2925 5425);
DISPLAY INVISIBLE (-2925 5425);
FORCEPROP 1 LAST PATH I170
J 0
(-3252 5550);
DISPLAY 0.872340 (-3252 5550);
PAINT GREEN (-3252 5550);
DISPLAY INVISIBLE (-3252 5550);
FORCEADD TAP..1
(-3250 5500);
FORCEPROP 3 LASTPIN (-3300 5500) SIG_NAME M_J_CPU0_SA_DQ<9>
J 0
(-3290 5510);
DISPLAY 0.659574 (-3290 5510);
PAINT MONO (-3290 5510);
DISPLAY INVISIBLE (-3290 5510);
FORCEPROP 1 LASTPIN (-3300 5500) BN 9
J 0
(-3312 5508);
DISPLAY 0.489362 (-3312 5508);
PAINT GREEN (-3312 5508);
FORCEPROP 2 LAST CDS_LIB mstr_standard
J 0
(-3250 5500);
DISPLAY 0.723404 (-3250 5500);
PAINT MONO (-3250 5500);
DISPLAY INVISIBLE (-3250 5500);
FORCEPROP 1 LAST BODY_TYPE PLUMBING
J 0
(-3250 5550);
DISPLAY 0.872340 (-3250 5550);
PAINT GREEN (-3250 5550);
DISPLAY INVISIBLE (-3250 5550);
FORCEPROP 1 LAST HDL_TAP TRUE
J 0
(-2925 5375);
DISPLAY 0.872340 (-2925 5375);
DISPLAY INVISIBLE (-2925 5375);
FORCEPROP 1 LAST PATH I171
J 0
(-3252 5500);
DISPLAY 0.872340 (-3252 5500);
PAINT GREEN (-3252 5500);
DISPLAY INVISIBLE (-3252 5500);
FORCEADD TAP..1
(-3250 5450);
FORCEPROP 3 LASTPIN (-3300 5450) SIG_NAME M_J_CPU0_SA_DQ<10>
J 0
(-3290 5460);
DISPLAY 0.659574 (-3290 5460);
PAINT MONO (-3290 5460);
DISPLAY INVISIBLE (-3290 5460);
FORCEPROP 1 LASTPIN (-3300 5450) BN 10
J 0
(-3312 5458);
DISPLAY 0.489362 (-3312 5458);
PAINT GREEN (-3312 5458);
FORCEPROP 2 LAST CDS_LIB mstr_standard
J 0
(-3250 5450);
DISPLAY 0.723404 (-3250 5450);
PAINT MONO (-3250 5450);
DISPLAY INVISIBLE (-3250 5450);
FORCEPROP 1 LAST BODY_TYPE PLUMBING
J 0
(-3250 5500);
DISPLAY 0.872340 (-3250 5500);
PAINT GREEN (-3250 5500);
DISPLAY INVISIBLE (-3250 5500);
FORCEPROP 1 LAST HDL_TAP TRUE
J 0
(-2925 5325);
DISPLAY 0.872340 (-2925 5325);
DISPLAY INVISIBLE (-2925 5325);
FORCEPROP 1 LAST PATH I172
J 0
(-3252 5450);
DISPLAY 0.872340 (-3252 5450);
PAINT GREEN (-3252 5450);
DISPLAY INVISIBLE (-3252 5450);
FORCEADD TAP..1
(-3250 5400);
FORCEPROP 3 LASTPIN (-3300 5400) SIG_NAME M_J_CPU0_SA_DQ<11>
J 0
(-3290 5410);
DISPLAY 0.659574 (-3290 5410);
PAINT MONO (-3290 5410);
DISPLAY INVISIBLE (-3290 5410);
FORCEPROP 1 LASTPIN (-3300 5400) BN 11
J 0
(-3312 5408);
DISPLAY 0.489362 (-3312 5408);
PAINT GREEN (-3312 5408);
FORCEPROP 2 LAST CDS_LIB mstr_standard
J 0
(-3250 5400);
DISPLAY 0.723404 (-3250 5400);
PAINT MONO (-3250 5400);
DISPLAY INVISIBLE (-3250 5400);
FORCEPROP 1 LAST BODY_TYPE PLUMBING
J 0
(-3250 5450);
DISPLAY 0.872340 (-3250 5450);
PAINT GREEN (-3250 5450);
DISPLAY INVISIBLE (-3250 5450);
FORCEPROP 1 LAST HDL_TAP TRUE
J 0
(-2925 5275);
DISPLAY 0.872340 (-2925 5275);
DISPLAY INVISIBLE (-2925 5275);
FORCEPROP 1 LAST PATH I173
J 0
(-3252 5400);
DISPLAY 0.872340 (-3252 5400);
PAINT GREEN (-3252 5400);
DISPLAY INVISIBLE (-3252 5400);
FORCEADD TAP..1
(-3250 5350);
FORCEPROP 3 LASTPIN (-3300 5350) SIG_NAME M_J_CPU0_SA_DQ<12>
J 0
(-3290 5360);
DISPLAY 0.659574 (-3290 5360);
PAINT MONO (-3290 5360);
DISPLAY INVISIBLE (-3290 5360);
FORCEPROP 1 LASTPIN (-3300 5350) BN 12
J 0
(-3312 5358);
DISPLAY 0.489362 (-3312 5358);
PAINT GREEN (-3312 5358);
FORCEPROP 2 LAST CDS_LIB mstr_standard
J 0
(-3250 5350);
DISPLAY 0.723404 (-3250 5350);
PAINT MONO (-3250 5350);
DISPLAY INVISIBLE (-3250 5350);
FORCEPROP 1 LAST BODY_TYPE PLUMBING
J 0
(-3250 5400);
DISPLAY 0.872340 (-3250 5400);
PAINT GREEN (-3250 5400);
DISPLAY INVISIBLE (-3250 5400);
FORCEPROP 1 LAST HDL_TAP TRUE
J 0
(-2925 5225);
DISPLAY 0.872340 (-2925 5225);
DISPLAY INVISIBLE (-2925 5225);
FORCEPROP 1 LAST PATH I174
J 0
(-3252 5350);
DISPLAY 0.872340 (-3252 5350);
PAINT GREEN (-3252 5350);
DISPLAY INVISIBLE (-3252 5350);
FORCEADD TAP..1
(-3250 5300);
FORCEPROP 3 LASTPIN (-3300 5300) SIG_NAME M_J_CPU0_SA_DQ<13>
J 0
(-3290 5310);
DISPLAY 0.659574 (-3290 5310);
PAINT MONO (-3290 5310);
DISPLAY INVISIBLE (-3290 5310);
FORCEPROP 1 LASTPIN (-3300 5300) BN 13
J 0
(-3312 5308);
DISPLAY 0.489362 (-3312 5308);
PAINT GREEN (-3312 5308);
FORCEPROP 2 LAST CDS_LIB mstr_standard
J 0
(-3250 5300);
DISPLAY 0.723404 (-3250 5300);
PAINT MONO (-3250 5300);
DISPLAY INVISIBLE (-3250 5300);
FORCEPROP 1 LAST BODY_TYPE PLUMBING
J 0
(-3250 5350);
DISPLAY 0.872340 (-3250 5350);
PAINT GREEN (-3250 5350);
DISPLAY INVISIBLE (-3250 5350);
FORCEPROP 1 LAST HDL_TAP TRUE
J 0
(-2925 5175);
DISPLAY 0.872340 (-2925 5175);
DISPLAY INVISIBLE (-2925 5175);
FORCEPROP 1 LAST PATH I175
J 0
(-3252 5300);
DISPLAY 0.872340 (-3252 5300);
PAINT GREEN (-3252 5300);
DISPLAY INVISIBLE (-3252 5300);
FORCEADD TAP..1
(-3250 5250);
FORCEPROP 3 LASTPIN (-3300 5250) SIG_NAME M_J_CPU0_SA_DQ<14>
J 0
(-3290 5260);
DISPLAY 0.659574 (-3290 5260);
PAINT MONO (-3290 5260);
DISPLAY INVISIBLE (-3290 5260);
FORCEPROP 1 LASTPIN (-3300 5250) BN 14
J 0
(-3312 5258);
DISPLAY 0.489362 (-3312 5258);
PAINT GREEN (-3312 5258);
FORCEPROP 2 LAST CDS_LIB mstr_standard
J 0
(-3250 5250);
DISPLAY 0.723404 (-3250 5250);
PAINT MONO (-3250 5250);
DISPLAY INVISIBLE (-3250 5250);
FORCEPROP 1 LAST BODY_TYPE PLUMBING
J 0
(-3250 5300);
DISPLAY 0.872340 (-3250 5300);
PAINT GREEN (-3250 5300);
DISPLAY INVISIBLE (-3250 5300);
FORCEPROP 1 LAST HDL_TAP TRUE
J 0
(-2925 5125);
DISPLAY 0.872340 (-2925 5125);
DISPLAY INVISIBLE (-2925 5125);
FORCEPROP 1 LAST PATH I176
J 0
(-3252 5250);
DISPLAY 0.872340 (-3252 5250);
PAINT GREEN (-3252 5250);
DISPLAY INVISIBLE (-3252 5250);
FORCEADD TAP..1
(-3250 5200);
FORCEPROP 3 LASTPIN (-3300 5200) SIG_NAME M_J_CPU0_SA_DQ<15>
J 0
(-3290 5210);
DISPLAY 0.659574 (-3290 5210);
PAINT MONO (-3290 5210);
DISPLAY INVISIBLE (-3290 5210);
FORCEPROP 1 LASTPIN (-3300 5200) BN 15
J 0
(-3312 5208);
DISPLAY 0.489362 (-3312 5208);
PAINT GREEN (-3312 5208);
FORCEPROP 2 LAST CDS_LIB mstr_standard
J 0
(-3250 5200);
DISPLAY 0.723404 (-3250 5200);
PAINT MONO (-3250 5200);
DISPLAY INVISIBLE (-3250 5200);
FORCEPROP 1 LAST BODY_TYPE PLUMBING
J 0
(-3250 5250);
DISPLAY 0.872340 (-3250 5250);
PAINT GREEN (-3250 5250);
DISPLAY INVISIBLE (-3250 5250);
FORCEPROP 1 LAST HDL_TAP TRUE
J 0
(-2925 5075);
DISPLAY 0.872340 (-2925 5075);
DISPLAY INVISIBLE (-2925 5075);
FORCEPROP 1 LAST PATH I177
J 0
(-3252 5200);
DISPLAY 0.872340 (-3252 5200);
PAINT GREEN (-3252 5200);
DISPLAY INVISIBLE (-3252 5200);
FORCEADD TAP..1
(-3250 5000);
FORCEPROP 3 LASTPIN (-3300 5000) SIG_NAME M_J_CPU0_SA_DQ<18>
J 0
(-3290 5010);
DISPLAY 0.659574 (-3290 5010);
PAINT MONO (-3290 5010);
DISPLAY INVISIBLE (-3290 5010);
FORCEPROP 1 LASTPIN (-3300 5000) BN 18
J 0
(-3312 5008);
DISPLAY 0.489362 (-3312 5008);
PAINT GREEN (-3312 5008);
FORCEPROP 2 LAST CDS_LIB mstr_standard
J 0
(-3250 5000);
DISPLAY 0.723404 (-3250 5000);
PAINT MONO (-3250 5000);
DISPLAY INVISIBLE (-3250 5000);
FORCEPROP 1 LAST BODY_TYPE PLUMBING
J 0
(-3250 5050);
DISPLAY 0.872340 (-3250 5050);
PAINT GREEN (-3250 5050);
DISPLAY INVISIBLE (-3250 5050);
FORCEPROP 1 LAST HDL_TAP TRUE
J 0
(-2925 4875);
DISPLAY 0.872340 (-2925 4875);
DISPLAY INVISIBLE (-2925 4875);
FORCEPROP 1 LAST PATH I178
J 0
(-3252 5000);
DISPLAY 0.872340 (-3252 5000);
PAINT GREEN (-3252 5000);
DISPLAY INVISIBLE (-3252 5000);
FORCEADD TAP..1
(-3250 5100);
FORCEPROP 3 LASTPIN (-3300 5100) SIG_NAME M_J_CPU0_SA_DQ<16>
J 0
(-3290 5110);
DISPLAY 0.659574 (-3290 5110);
PAINT MONO (-3290 5110);
DISPLAY INVISIBLE (-3290 5110);
FORCEPROP 1 LASTPIN (-3300 5100) BN 16
J 0
(-3312 5108);
DISPLAY 0.489362 (-3312 5108);
PAINT GREEN (-3312 5108);
FORCEPROP 2 LAST CDS_LIB mstr_standard
J 0
(-3250 5100);
DISPLAY 0.723404 (-3250 5100);
PAINT MONO (-3250 5100);
DISPLAY INVISIBLE (-3250 5100);
FORCEPROP 1 LAST BODY_TYPE PLUMBING
J 0
(-3250 5150);
DISPLAY 0.872340 (-3250 5150);
PAINT GREEN (-3250 5150);
DISPLAY INVISIBLE (-3250 5150);
FORCEPROP 1 LAST HDL_TAP TRUE
J 0
(-2925 4975);
DISPLAY 0.872340 (-2925 4975);
DISPLAY INVISIBLE (-2925 4975);
FORCEPROP 1 LAST PATH I179
J 0
(-3252 5100);
DISPLAY 0.872340 (-3252 5100);
PAINT GREEN (-3252 5100);
DISPLAY INVISIBLE (-3252 5100);
FORCEADD TAP..1
(-3250 5050);
FORCEPROP 3 LASTPIN (-3300 5050) SIG_NAME M_J_CPU0_SA_DQ<17>
J 0
(-3290 5060);
DISPLAY 0.659574 (-3290 5060);
PAINT MONO (-3290 5060);
DISPLAY INVISIBLE (-3290 5060);
FORCEPROP 1 LASTPIN (-3300 5050) BN 17
J 0
(-3312 5058);
DISPLAY 0.489362 (-3312 5058);
PAINT GREEN (-3312 5058);
FORCEPROP 2 LAST CDS_LIB mstr_standard
J 0
(-3250 5050);
DISPLAY 0.723404 (-3250 5050);
PAINT MONO (-3250 5050);
DISPLAY INVISIBLE (-3250 5050);
FORCEPROP 1 LAST BODY_TYPE PLUMBING
J 0
(-3250 5100);
DISPLAY 0.872340 (-3250 5100);
PAINT GREEN (-3250 5100);
DISPLAY INVISIBLE (-3250 5100);
FORCEPROP 1 LAST HDL_TAP TRUE
J 0
(-2925 4925);
DISPLAY 0.872340 (-2925 4925);
DISPLAY INVISIBLE (-2925 4925);
FORCEPROP 1 LAST PATH I180
J 0
(-3252 5050);
DISPLAY 0.872340 (-3252 5050);
PAINT GREEN (-3252 5050);
DISPLAY INVISIBLE (-3252 5050);
FORCEADD TAP..1
(-3250 4950);
FORCEPROP 3 LASTPIN (-3300 4950) SIG_NAME M_J_CPU0_SA_DQ<19>
J 0
(-3290 4960);
DISPLAY 0.659574 (-3290 4960);
PAINT MONO (-3290 4960);
DISPLAY INVISIBLE (-3290 4960);
FORCEPROP 1 LASTPIN (-3300 4950) BN 19
J 0
(-3312 4958);
DISPLAY 0.489362 (-3312 4958);
PAINT GREEN (-3312 4958);
FORCEPROP 2 LAST CDS_LIB mstr_standard
J 0
(-3250 4950);
DISPLAY 0.723404 (-3250 4950);
PAINT MONO (-3250 4950);
DISPLAY INVISIBLE (-3250 4950);
FORCEPROP 1 LAST BODY_TYPE PLUMBING
J 0
(-3250 5000);
DISPLAY 0.872340 (-3250 5000);
PAINT GREEN (-3250 5000);
DISPLAY INVISIBLE (-3250 5000);
FORCEPROP 1 LAST HDL_TAP TRUE
J 0
(-2925 4825);
DISPLAY 0.872340 (-2925 4825);
DISPLAY INVISIBLE (-2925 4825);
FORCEPROP 1 LAST PATH I181
J 0
(-3252 4950);
DISPLAY 0.872340 (-3252 4950);
PAINT GREEN (-3252 4950);
DISPLAY INVISIBLE (-3252 4950);
FORCEADD TAP..1
(-3250 4900);
FORCEPROP 3 LASTPIN (-3300 4900) SIG_NAME M_J_CPU0_SA_DQ<20>
J 0
(-3290 4910);
DISPLAY 0.659574 (-3290 4910);
PAINT MONO (-3290 4910);
DISPLAY INVISIBLE (-3290 4910);
FORCEPROP 1 LASTPIN (-3300 4900) BN 20
J 0
(-3312 4908);
DISPLAY 0.489362 (-3312 4908);
PAINT GREEN (-3312 4908);
FORCEPROP 2 LAST CDS_LIB mstr_standard
J 0
(-3250 4900);
DISPLAY 0.723404 (-3250 4900);
PAINT MONO (-3250 4900);
DISPLAY INVISIBLE (-3250 4900);
FORCEPROP 1 LAST BODY_TYPE PLUMBING
J 0
(-3250 4950);
DISPLAY 0.872340 (-3250 4950);
PAINT GREEN (-3250 4950);
DISPLAY INVISIBLE (-3250 4950);
FORCEPROP 1 LAST HDL_TAP TRUE
J 0
(-2925 4775);
DISPLAY 0.872340 (-2925 4775);
DISPLAY INVISIBLE (-2925 4775);
FORCEPROP 1 LAST PATH I182
J 0
(-3252 4900);
DISPLAY 0.872340 (-3252 4900);
PAINT GREEN (-3252 4900);
DISPLAY INVISIBLE (-3252 4900);
FORCEADD TAP..1
(-3250 4800);
FORCEPROP 3 LASTPIN (-3300 4800) SIG_NAME M_J_CPU0_SA_DQ<22>
J 0
(-3290 4810);
DISPLAY 0.659574 (-3290 4810);
PAINT MONO (-3290 4810);
DISPLAY INVISIBLE (-3290 4810);
FORCEPROP 1 LASTPIN (-3300 4800) BN 22
J 0
(-3312 4808);
DISPLAY 0.489362 (-3312 4808);
PAINT GREEN (-3312 4808);
FORCEPROP 2 LAST CDS_LIB mstr_standard
J 0
(-3250 4800);
DISPLAY 0.723404 (-3250 4800);
PAINT MONO (-3250 4800);
DISPLAY INVISIBLE (-3250 4800);
FORCEPROP 1 LAST BODY_TYPE PLUMBING
J 0
(-3250 4850);
DISPLAY 0.872340 (-3250 4850);
PAINT GREEN (-3250 4850);
DISPLAY INVISIBLE (-3250 4850);
FORCEPROP 1 LAST HDL_TAP TRUE
J 0
(-2925 4675);
DISPLAY 0.872340 (-2925 4675);
DISPLAY INVISIBLE (-2925 4675);
FORCEPROP 1 LAST PATH I183
J 0
(-3252 4800);
DISPLAY 0.872340 (-3252 4800);
PAINT GREEN (-3252 4800);
DISPLAY INVISIBLE (-3252 4800);
FORCEADD TAP..1
(-3250 4850);
FORCEPROP 3 LASTPIN (-3300 4850) SIG_NAME M_J_CPU0_SA_DQ<21>
J 0
(-3290 4860);
DISPLAY 0.659574 (-3290 4860);
PAINT MONO (-3290 4860);
DISPLAY INVISIBLE (-3290 4860);
FORCEPROP 1 LASTPIN (-3300 4850) BN 21
J 0
(-3312 4858);
DISPLAY 0.489362 (-3312 4858);
PAINT GREEN (-3312 4858);
FORCEPROP 2 LAST CDS_LIB mstr_standard
J 0
(-3250 4850);
DISPLAY 0.723404 (-3250 4850);
PAINT MONO (-3250 4850);
DISPLAY INVISIBLE (-3250 4850);
FORCEPROP 1 LAST BODY_TYPE PLUMBING
J 0
(-3250 4900);
DISPLAY 0.872340 (-3250 4900);
PAINT GREEN (-3250 4900);
DISPLAY INVISIBLE (-3250 4900);
FORCEPROP 1 LAST HDL_TAP TRUE
J 0
(-2925 4725);
DISPLAY 0.872340 (-2925 4725);
DISPLAY INVISIBLE (-2925 4725);
FORCEPROP 1 LAST PATH I184
J 0
(-3252 4850);
DISPLAY 0.872340 (-3252 4850);
PAINT GREEN (-3252 4850);
DISPLAY INVISIBLE (-3252 4850);
FORCEADD TAP..1
(-3250 4750);
FORCEPROP 3 LASTPIN (-3300 4750) SIG_NAME M_J_CPU0_SA_DQ<23>
J 0
(-3290 4760);
DISPLAY 0.659574 (-3290 4760);
PAINT MONO (-3290 4760);
DISPLAY INVISIBLE (-3290 4760);
FORCEPROP 1 LASTPIN (-3300 4750) BN 23
J 0
(-3312 4758);
DISPLAY 0.489362 (-3312 4758);
PAINT GREEN (-3312 4758);
FORCEPROP 2 LAST CDS_LIB mstr_standard
J 0
(-3250 4750);
DISPLAY 0.723404 (-3250 4750);
PAINT MONO (-3250 4750);
DISPLAY INVISIBLE (-3250 4750);
FORCEPROP 1 LAST BODY_TYPE PLUMBING
J 0
(-3250 4800);
DISPLAY 0.872340 (-3250 4800);
PAINT GREEN (-3250 4800);
DISPLAY INVISIBLE (-3250 4800);
FORCEPROP 1 LAST HDL_TAP TRUE
J 0
(-2925 4625);
DISPLAY 0.872340 (-2925 4625);
DISPLAY INVISIBLE (-2925 4625);
FORCEPROP 1 LAST PATH I185
J 0
(-3252 4750);
DISPLAY 0.872340 (-3252 4750);
PAINT GREEN (-3252 4750);
DISPLAY INVISIBLE (-3252 4750);
FORCEADD TAP..1
(-3250 4650);
FORCEPROP 3 LASTPIN (-3300 4650) SIG_NAME M_J_CPU0_SA_DQ<24>
J 0
(-3290 4660);
DISPLAY 0.659574 (-3290 4660);
PAINT MONO (-3290 4660);
DISPLAY INVISIBLE (-3290 4660);
FORCEPROP 1 LASTPIN (-3300 4650) BN 24
J 0
(-3312 4658);
DISPLAY 0.489362 (-3312 4658);
PAINT GREEN (-3312 4658);
FORCEPROP 2 LAST CDS_LIB mstr_standard
J 0
(-3250 4650);
DISPLAY 0.723404 (-3250 4650);
PAINT MONO (-3250 4650);
DISPLAY INVISIBLE (-3250 4650);
FORCEPROP 1 LAST BODY_TYPE PLUMBING
J 0
(-3250 4700);
DISPLAY 0.872340 (-3250 4700);
PAINT GREEN (-3250 4700);
DISPLAY INVISIBLE (-3250 4700);
FORCEPROP 1 LAST HDL_TAP TRUE
J 0
(-2925 4525);
DISPLAY 0.872340 (-2925 4525);
DISPLAY INVISIBLE (-2925 4525);
FORCEPROP 1 LAST PATH I186
J 0
(-3252 4650);
DISPLAY 0.872340 (-3252 4650);
PAINT GREEN (-3252 4650);
DISPLAY INVISIBLE (-3252 4650);
FORCEADD TAP..1
(-3250 4500);
FORCEPROP 3 LASTPIN (-3300 4500) SIG_NAME M_J_CPU0_SA_DQ<27>
J 0
(-3290 4510);
DISPLAY 0.659574 (-3290 4510);
PAINT MONO (-3290 4510);
DISPLAY INVISIBLE (-3290 4510);
FORCEPROP 1 LASTPIN (-3300 4500) BN 27
J 0
(-3312 4508);
DISPLAY 0.489362 (-3312 4508);
PAINT GREEN (-3312 4508);
FORCEPROP 2 LAST CDS_LIB mstr_standard
J 0
(-3250 4500);
DISPLAY 0.723404 (-3250 4500);
PAINT MONO (-3250 4500);
DISPLAY INVISIBLE (-3250 4500);
FORCEPROP 1 LAST BODY_TYPE PLUMBING
J 0
(-3250 4550);
DISPLAY 0.872340 (-3250 4550);
PAINT GREEN (-3250 4550);
DISPLAY INVISIBLE (-3250 4550);
FORCEPROP 1 LAST HDL_TAP TRUE
J 0
(-2925 4375);
DISPLAY 0.872340 (-2925 4375);
DISPLAY INVISIBLE (-2925 4375);
FORCEPROP 1 LAST PATH I187
J 0
(-3252 4500);
DISPLAY 0.872340 (-3252 4500);
PAINT GREEN (-3252 4500);
DISPLAY INVISIBLE (-3252 4500);
FORCEADD TAP..1
(-3250 4550);
FORCEPROP 3 LASTPIN (-3300 4550) SIG_NAME M_J_CPU0_SA_DQ<26>
J 0
(-3290 4560);
DISPLAY 0.659574 (-3290 4560);
PAINT MONO (-3290 4560);
DISPLAY INVISIBLE (-3290 4560);
FORCEPROP 1 LASTPIN (-3300 4550) BN 26
J 0
(-3312 4558);
DISPLAY 0.489362 (-3312 4558);
PAINT GREEN (-3312 4558);
FORCEPROP 2 LAST CDS_LIB mstr_standard
J 0
(-3250 4550);
DISPLAY 0.723404 (-3250 4550);
PAINT MONO (-3250 4550);
DISPLAY INVISIBLE (-3250 4550);
FORCEPROP 1 LAST BODY_TYPE PLUMBING
J 0
(-3250 4600);
DISPLAY 0.872340 (-3250 4600);
PAINT GREEN (-3250 4600);
DISPLAY INVISIBLE (-3250 4600);
FORCEPROP 1 LAST HDL_TAP TRUE
J 0
(-2925 4425);
DISPLAY 0.872340 (-2925 4425);
DISPLAY INVISIBLE (-2925 4425);
FORCEPROP 1 LAST PATH I188
J 0
(-3252 4550);
DISPLAY 0.872340 (-3252 4550);
PAINT GREEN (-3252 4550);
DISPLAY INVISIBLE (-3252 4550);
FORCEADD TAP..1
(-3250 4600);
FORCEPROP 3 LASTPIN (-3300 4600) SIG_NAME M_J_CPU0_SA_DQ<25>
J 0
(-3290 4610);
DISPLAY 0.659574 (-3290 4610);
PAINT MONO (-3290 4610);
DISPLAY INVISIBLE (-3290 4610);
FORCEPROP 1 LASTPIN (-3300 4600) BN 25
J 0
(-3312 4608);
DISPLAY 0.489362 (-3312 4608);
PAINT GREEN (-3312 4608);
FORCEPROP 2 LAST CDS_LIB mstr_standard
J 0
(-3250 4600);
DISPLAY 0.723404 (-3250 4600);
PAINT MONO (-3250 4600);
DISPLAY INVISIBLE (-3250 4600);
FORCEPROP 1 LAST BODY_TYPE PLUMBING
J 0
(-3250 4650);
DISPLAY 0.872340 (-3250 4650);
PAINT GREEN (-3250 4650);
DISPLAY INVISIBLE (-3250 4650);
FORCEPROP 1 LAST HDL_TAP TRUE
J 0
(-2925 4475);
DISPLAY 0.872340 (-2925 4475);
DISPLAY INVISIBLE (-2925 4475);
FORCEPROP 1 LAST PATH I189
J 0
(-3252 4600);
DISPLAY 0.872340 (-3252 4600);
PAINT GREEN (-3252 4600);
DISPLAY INVISIBLE (-3252 4600);
FORCEADD TAP..1
(-3250 4450);
FORCEPROP 3 LASTPIN (-3300 4450) SIG_NAME M_J_CPU0_SA_DQ<28>
J 0
(-3290 4460);
DISPLAY 0.659574 (-3290 4460);
PAINT MONO (-3290 4460);
DISPLAY INVISIBLE (-3290 4460);
FORCEPROP 1 LASTPIN (-3300 4450) BN 28
J 0
(-3312 4458);
DISPLAY 0.489362 (-3312 4458);
PAINT GREEN (-3312 4458);
FORCEPROP 2 LAST CDS_LIB mstr_standard
J 0
(-3250 4450);
DISPLAY 0.723404 (-3250 4450);
PAINT MONO (-3250 4450);
DISPLAY INVISIBLE (-3250 4450);
FORCEPROP 1 LAST BODY_TYPE PLUMBING
J 0
(-3250 4500);
DISPLAY 0.872340 (-3250 4500);
PAINT GREEN (-3250 4500);
DISPLAY INVISIBLE (-3250 4500);
FORCEPROP 1 LAST HDL_TAP TRUE
J 0
(-2925 4325);
DISPLAY 0.872340 (-2925 4325);
DISPLAY INVISIBLE (-2925 4325);
FORCEPROP 1 LAST PATH I190
J 0
(-3252 4450);
DISPLAY 0.872340 (-3252 4450);
PAINT GREEN (-3252 4450);
DISPLAY INVISIBLE (-3252 4450);
FORCEADD TAP..1
(-3250 4400);
FORCEPROP 3 LASTPIN (-3300 4400) SIG_NAME M_J_CPU0_SA_DQ<29>
J 0
(-3290 4410);
DISPLAY 0.659574 (-3290 4410);
PAINT MONO (-3290 4410);
DISPLAY INVISIBLE (-3290 4410);
FORCEPROP 1 LASTPIN (-3300 4400) BN 29
J 0
(-3312 4408);
DISPLAY 0.489362 (-3312 4408);
PAINT GREEN (-3312 4408);
FORCEPROP 2 LAST CDS_LIB mstr_standard
J 0
(-3250 4400);
DISPLAY 0.723404 (-3250 4400);
PAINT MONO (-3250 4400);
DISPLAY INVISIBLE (-3250 4400);
FORCEPROP 1 LAST BODY_TYPE PLUMBING
J 0
(-3250 4450);
DISPLAY 0.872340 (-3250 4450);
PAINT GREEN (-3250 4450);
DISPLAY INVISIBLE (-3250 4450);
FORCEPROP 1 LAST HDL_TAP TRUE
J 0
(-2925 4275);
DISPLAY 0.872340 (-2925 4275);
DISPLAY INVISIBLE (-2925 4275);
FORCEPROP 1 LAST PATH I191
J 0
(-3252 4400);
DISPLAY 0.872340 (-3252 4400);
PAINT GREEN (-3252 4400);
DISPLAY INVISIBLE (-3252 4400);
FORCEADD TAP..1
(-3250 4300);
FORCEPROP 3 LASTPIN (-3300 4300) SIG_NAME M_J_CPU0_SA_DQ<31>
J 0
(-3290 4310);
DISPLAY 0.659574 (-3290 4310);
PAINT MONO (-3290 4310);
DISPLAY INVISIBLE (-3290 4310);
FORCEPROP 1 LASTPIN (-3300 4300) BN 31
J 0
(-3312 4308);
DISPLAY 0.489362 (-3312 4308);
PAINT GREEN (-3312 4308);
FORCEPROP 2 LAST CDS_LIB mstr_standard
J 0
(-3250 4300);
DISPLAY 0.723404 (-3250 4300);
PAINT MONO (-3250 4300);
DISPLAY INVISIBLE (-3250 4300);
FORCEPROP 1 LAST BODY_TYPE PLUMBING
J 0
(-3250 4350);
DISPLAY 0.872340 (-3250 4350);
PAINT GREEN (-3250 4350);
DISPLAY INVISIBLE (-3250 4350);
FORCEPROP 1 LAST HDL_TAP TRUE
J 0
(-2925 4175);
DISPLAY 0.872340 (-2925 4175);
DISPLAY INVISIBLE (-2925 4175);
FORCEPROP 1 LAST PATH I192
J 0
(-3252 4300);
DISPLAY 0.872340 (-3252 4300);
PAINT GREEN (-3252 4300);
DISPLAY INVISIBLE (-3252 4300);
FORCEADD TAP..1
(-3250 4350);
FORCEPROP 3 LASTPIN (-3300 4350) SIG_NAME M_J_CPU0_SA_DQ<30>
J 0
(-3290 4360);
DISPLAY 0.659574 (-3290 4360);
PAINT MONO (-3290 4360);
DISPLAY INVISIBLE (-3290 4360);
FORCEPROP 1 LASTPIN (-3300 4350) BN 30
J 0
(-3312 4358);
DISPLAY 0.489362 (-3312 4358);
PAINT GREEN (-3312 4358);
FORCEPROP 2 LAST CDS_LIB mstr_standard
J 0
(-3250 4350);
DISPLAY 0.723404 (-3250 4350);
PAINT MONO (-3250 4350);
DISPLAY INVISIBLE (-3250 4350);
FORCEPROP 1 LAST BODY_TYPE PLUMBING
J 0
(-3250 4400);
DISPLAY 0.872340 (-3250 4400);
PAINT GREEN (-3250 4400);
DISPLAY INVISIBLE (-3250 4400);
FORCEPROP 1 LAST HDL_TAP TRUE
J 0
(-2925 4225);
DISPLAY 0.872340 (-2925 4225);
DISPLAY INVISIBLE (-2925 4225);
FORCEPROP 1 LAST PATH I193
J 0
(-3252 4350);
DISPLAY 0.872340 (-3252 4350);
PAINT GREEN (-3252 4350);
DISPLAY INVISIBLE (-3252 4350);
FORCEADD TAP..1
(-3250 4200);
FORCEPROP 3 LASTPIN (-3300 4200) SIG_NAME M_J_CPU0_SB_DQ<0>
J 0
(-3290 4210);
DISPLAY 0.659574 (-3290 4210);
PAINT MONO (-3290 4210);
DISPLAY INVISIBLE (-3290 4210);
FORCEPROP 1 LASTPIN (-3300 4200) BN 0
J 0
(-3312 4208);
DISPLAY 0.489362 (-3312 4208);
PAINT GREEN (-3312 4208);
FORCEPROP 2 LAST CDS_LIB mstr_standard
J 0
(-3250 4200);
DISPLAY 0.723404 (-3250 4200);
PAINT MONO (-3250 4200);
DISPLAY INVISIBLE (-3250 4200);
FORCEPROP 1 LAST BODY_TYPE PLUMBING
J 0
(-3250 4250);
DISPLAY 0.872340 (-3250 4250);
PAINT GREEN (-3250 4250);
DISPLAY INVISIBLE (-3250 4250);
FORCEPROP 1 LAST HDL_TAP TRUE
J 0
(-2925 4075);
DISPLAY 0.872340 (-2925 4075);
DISPLAY INVISIBLE (-2925 4075);
FORCEPROP 1 LAST PATH I194
J 0
(-3252 4200);
DISPLAY 0.872340 (-3252 4200);
PAINT GREEN (-3252 4200);
DISPLAY INVISIBLE (-3252 4200);
FORCEADD TAP..1
(-3250 4150);
FORCEPROP 3 LASTPIN (-3300 4150) SIG_NAME M_J_CPU0_SB_DQ<1>
J 0
(-3290 4160);
DISPLAY 0.659574 (-3290 4160);
PAINT MONO (-3290 4160);
DISPLAY INVISIBLE (-3290 4160);
FORCEPROP 1 LASTPIN (-3300 4150) BN 1
J 0
(-3312 4158);
DISPLAY 0.489362 (-3312 4158);
PAINT GREEN (-3312 4158);
FORCEPROP 2 LAST CDS_LIB mstr_standard
J 0
(-3250 4150);
DISPLAY 0.723404 (-3250 4150);
PAINT MONO (-3250 4150);
DISPLAY INVISIBLE (-3250 4150);
FORCEPROP 1 LAST BODY_TYPE PLUMBING
J 0
(-3250 4200);
DISPLAY 0.872340 (-3250 4200);
PAINT GREEN (-3250 4200);
DISPLAY INVISIBLE (-3250 4200);
FORCEPROP 1 LAST HDL_TAP TRUE
J 0
(-2925 4025);
DISPLAY 0.872340 (-2925 4025);
DISPLAY INVISIBLE (-2925 4025);
FORCEPROP 1 LAST PATH I195
J 0
(-3252 4150);
DISPLAY 0.872340 (-3252 4150);
PAINT GREEN (-3252 4150);
DISPLAY INVISIBLE (-3252 4150);
FORCEADD TAP..1
(-3250 4100);
FORCEPROP 3 LASTPIN (-3300 4100) SIG_NAME M_J_CPU0_SB_DQ<2>
J 0
(-3290 4110);
DISPLAY 0.659574 (-3290 4110);
PAINT MONO (-3290 4110);
DISPLAY INVISIBLE (-3290 4110);
FORCEPROP 1 LASTPIN (-3300 4100) BN 2
J 0
(-3312 4108);
DISPLAY 0.489362 (-3312 4108);
PAINT GREEN (-3312 4108);
FORCEPROP 2 LAST CDS_LIB mstr_standard
J 0
(-3250 4100);
DISPLAY 0.723404 (-3250 4100);
PAINT MONO (-3250 4100);
DISPLAY INVISIBLE (-3250 4100);
FORCEPROP 1 LAST BODY_TYPE PLUMBING
J 0
(-3250 4150);
DISPLAY 0.872340 (-3250 4150);
PAINT GREEN (-3250 4150);
DISPLAY INVISIBLE (-3250 4150);
FORCEPROP 1 LAST HDL_TAP TRUE
J 0
(-2925 3975);
DISPLAY 0.872340 (-2925 3975);
DISPLAY INVISIBLE (-2925 3975);
FORCEPROP 1 LAST PATH I196
J 0
(-3252 4100);
DISPLAY 0.872340 (-3252 4100);
PAINT GREEN (-3252 4100);
DISPLAY INVISIBLE (-3252 4100);
FORCEADD OFFPAGE..6
R 2
(-2650 2450);
FORCEPROP 2 LAST $XR0 94 
J 0
(-2436 2450);
DISPLAY 0.638298 (-2436 2450);
PAINT MONO (-2436 2450);
FORCEPROP 2 LAST PATH I197
J 0
(-2425 2500);
DISPLAY 1.021277 (-2425 2500);
DISPLAY INVISIBLE (-2425 2500);
FORCEPROP 1 LAST COMMENT_BODY TRUE
J 2
(-2750 2375);
DISPLAY 0.872340 (-2750 2375);
PAINT GREEN (-2750 2375);
DISPLAY INVISIBLE (-2750 2375);
FORCEPROP 1 LAST OFFPAGE TRUE
J 2
(-2975 2325);
DISPLAY 0.872340 (-2975 2325);
PAINT GREEN (-2975 2325);
DISPLAY INVISIBLE (-2975 2325);
FORCEPROP 2 LAST CDS_LIB mstr_standard
J 2
(-2650 2450);
DISPLAY 0.723404 (-2650 2450);
PAINT MONO (-2650 2450);
DISPLAY INVISIBLE (-2650 2450);
FORCEADD TAP..1
(-3250 4050);
FORCEPROP 3 LASTPIN (-3300 4050) SIG_NAME M_J_CPU0_SB_DQ<3>
J 0
(-3290 4060);
DISPLAY 0.659574 (-3290 4060);
PAINT MONO (-3290 4060);
DISPLAY INVISIBLE (-3290 4060);
FORCEPROP 1 LASTPIN (-3300 4050) BN 3
J 0
(-3312 4058);
DISPLAY 0.489362 (-3312 4058);
PAINT GREEN (-3312 4058);
FORCEPROP 2 LAST CDS_LIB mstr_standard
J 0
(-3250 4050);
DISPLAY 0.723404 (-3250 4050);
PAINT MONO (-3250 4050);
DISPLAY INVISIBLE (-3250 4050);
FORCEPROP 1 LAST BODY_TYPE PLUMBING
J 0
(-3250 4100);
DISPLAY 0.872340 (-3250 4100);
PAINT GREEN (-3250 4100);
DISPLAY INVISIBLE (-3250 4100);
FORCEPROP 1 LAST HDL_TAP TRUE
J 0
(-2925 3925);
DISPLAY 0.872340 (-2925 3925);
DISPLAY INVISIBLE (-2925 3925);
FORCEPROP 1 LAST PATH I198
J 0
(-3252 4050);
DISPLAY 0.872340 (-3252 4050);
PAINT GREEN (-3252 4050);
DISPLAY INVISIBLE (-3252 4050);
FORCEADD TAP..1
(-3250 4000);
FORCEPROP 3 LASTPIN (-3300 4000) SIG_NAME M_J_CPU0_SB_DQ<4>
J 0
(-3290 4010);
DISPLAY 0.659574 (-3290 4010);
PAINT MONO (-3290 4010);
DISPLAY INVISIBLE (-3290 4010);
FORCEPROP 1 LASTPIN (-3300 4000) BN 4
J 0
(-3312 4008);
DISPLAY 0.489362 (-3312 4008);
PAINT GREEN (-3312 4008);
FORCEPROP 2 LAST CDS_LIB mstr_standard
J 0
(-3250 4000);
DISPLAY 0.723404 (-3250 4000);
PAINT MONO (-3250 4000);
DISPLAY INVISIBLE (-3250 4000);
FORCEPROP 1 LAST BODY_TYPE PLUMBING
J 0
(-3250 4050);
DISPLAY 0.872340 (-3250 4050);
PAINT GREEN (-3250 4050);
DISPLAY INVISIBLE (-3250 4050);
FORCEPROP 1 LAST HDL_TAP TRUE
J 0
(-2925 3875);
DISPLAY 0.872340 (-2925 3875);
DISPLAY INVISIBLE (-2925 3875);
FORCEPROP 1 LAST PATH I199
J 0
(-3252 4000);
DISPLAY 0.872340 (-3252 4000);
PAINT GREEN (-3252 4000);
DISPLAY INVISIBLE (-3252 4000);
FORCEADD TAP..1
(-3250 3850);
FORCEPROP 3 LASTPIN (-3300 3850) SIG_NAME M_J_CPU0_SB_DQ<7>
J 0
(-3290 3860);
DISPLAY 0.659574 (-3290 3860);
PAINT MONO (-3290 3860);
DISPLAY INVISIBLE (-3290 3860);
FORCEPROP 1 LASTPIN (-3300 3850) BN 7
J 0
(-3312 3858);
DISPLAY 0.489362 (-3312 3858);
PAINT GREEN (-3312 3858);
FORCEPROP 2 LAST CDS_LIB mstr_standard
J 0
(-3250 3850);
DISPLAY 0.723404 (-3250 3850);
PAINT MONO (-3250 3850);
DISPLAY INVISIBLE (-3250 3850);
FORCEPROP 1 LAST BODY_TYPE PLUMBING
J 0
(-3250 3900);
DISPLAY 0.872340 (-3250 3900);
PAINT GREEN (-3250 3900);
DISPLAY INVISIBLE (-3250 3900);
FORCEPROP 1 LAST HDL_TAP TRUE
J 0
(-2925 3725);
DISPLAY 0.872340 (-2925 3725);
DISPLAY INVISIBLE (-2925 3725);
FORCEPROP 1 LAST PATH I200
J 0
(-3252 3850);
DISPLAY 0.872340 (-3252 3850);
PAINT GREEN (-3252 3850);
DISPLAY INVISIBLE (-3252 3850);
FORCEADD TAP..1
(-3250 3900);
FORCEPROP 3 LASTPIN (-3300 3900) SIG_NAME M_J_CPU0_SB_DQ<6>
J 0
(-3290 3910);
DISPLAY 0.659574 (-3290 3910);
PAINT MONO (-3290 3910);
DISPLAY INVISIBLE (-3290 3910);
FORCEPROP 1 LASTPIN (-3300 3900) BN 6
J 0
(-3312 3908);
DISPLAY 0.489362 (-3312 3908);
PAINT GREEN (-3312 3908);
FORCEPROP 2 LAST CDS_LIB mstr_standard
J 0
(-3250 3900);
DISPLAY 0.723404 (-3250 3900);
PAINT MONO (-3250 3900);
DISPLAY INVISIBLE (-3250 3900);
FORCEPROP 1 LAST BODY_TYPE PLUMBING
J 0
(-3250 3950);
DISPLAY 0.872340 (-3250 3950);
PAINT GREEN (-3250 3950);
DISPLAY INVISIBLE (-3250 3950);
FORCEPROP 1 LAST HDL_TAP TRUE
J 0
(-2925 3775);
DISPLAY 0.872340 (-2925 3775);
DISPLAY INVISIBLE (-2925 3775);
FORCEPROP 1 LAST PATH I201
J 0
(-3252 3900);
DISPLAY 0.872340 (-3252 3900);
PAINT GREEN (-3252 3900);
DISPLAY INVISIBLE (-3252 3900);
FORCEADD TAP..1
(-3250 3950);
FORCEPROP 3 LASTPIN (-3300 3950) SIG_NAME M_J_CPU0_SB_DQ<5>
J 0
(-3290 3960);
DISPLAY 0.659574 (-3290 3960);
PAINT MONO (-3290 3960);
DISPLAY INVISIBLE (-3290 3960);
FORCEPROP 1 LASTPIN (-3300 3950) BN 5
J 0
(-3312 3958);
DISPLAY 0.489362 (-3312 3958);
PAINT GREEN (-3312 3958);
FORCEPROP 2 LAST CDS_LIB mstr_standard
J 0
(-3250 3950);
DISPLAY 0.723404 (-3250 3950);
PAINT MONO (-3250 3950);
DISPLAY INVISIBLE (-3250 3950);
FORCEPROP 1 LAST BODY_TYPE PLUMBING
J 0
(-3250 4000);
DISPLAY 0.872340 (-3250 4000);
PAINT GREEN (-3250 4000);
DISPLAY INVISIBLE (-3250 4000);
FORCEPROP 1 LAST HDL_TAP TRUE
J 0
(-2925 3825);
DISPLAY 0.872340 (-2925 3825);
DISPLAY INVISIBLE (-2925 3825);
FORCEPROP 1 LAST PATH I202
J 0
(-3252 3950);
DISPLAY 0.872340 (-3252 3950);
PAINT GREEN (-3252 3950);
DISPLAY INVISIBLE (-3252 3950);
FORCEADD TAP..1
(-3250 3750);
FORCEPROP 3 LASTPIN (-3300 3750) SIG_NAME M_J_CPU0_SB_DQ<8>
J 0
(-3290 3760);
DISPLAY 0.659574 (-3290 3760);
PAINT MONO (-3290 3760);
DISPLAY INVISIBLE (-3290 3760);
FORCEPROP 1 LASTPIN (-3300 3750) BN 8
J 0
(-3312 3758);
DISPLAY 0.489362 (-3312 3758);
PAINT GREEN (-3312 3758);
FORCEPROP 2 LAST CDS_LIB mstr_standard
J 0
(-3250 3750);
DISPLAY 0.723404 (-3250 3750);
PAINT MONO (-3250 3750);
DISPLAY INVISIBLE (-3250 3750);
FORCEPROP 1 LAST BODY_TYPE PLUMBING
J 0
(-3250 3800);
DISPLAY 0.872340 (-3250 3800);
PAINT GREEN (-3250 3800);
DISPLAY INVISIBLE (-3250 3800);
FORCEPROP 1 LAST HDL_TAP TRUE
J 0
(-2925 3625);
DISPLAY 0.872340 (-2925 3625);
DISPLAY INVISIBLE (-2925 3625);
FORCEPROP 1 LAST PATH I203
J 0
(-3252 3750);
DISPLAY 0.872340 (-3252 3750);
PAINT GREEN (-3252 3750);
DISPLAY INVISIBLE (-3252 3750);
FORCEADD TAP..1
(-3250 3700);
FORCEPROP 3 LASTPIN (-3300 3700) SIG_NAME M_J_CPU0_SB_DQ<9>
J 0
(-3290 3710);
DISPLAY 0.659574 (-3290 3710);
PAINT MONO (-3290 3710);
DISPLAY INVISIBLE (-3290 3710);
FORCEPROP 1 LASTPIN (-3300 3700) BN 9
J 0
(-3312 3708);
DISPLAY 0.489362 (-3312 3708);
PAINT GREEN (-3312 3708);
FORCEPROP 2 LAST CDS_LIB mstr_standard
J 0
(-3250 3700);
DISPLAY 0.723404 (-3250 3700);
PAINT MONO (-3250 3700);
DISPLAY INVISIBLE (-3250 3700);
FORCEPROP 1 LAST BODY_TYPE PLUMBING
J 0
(-3250 3750);
DISPLAY 0.872340 (-3250 3750);
PAINT GREEN (-3250 3750);
DISPLAY INVISIBLE (-3250 3750);
FORCEPROP 1 LAST HDL_TAP TRUE
J 0
(-2925 3575);
DISPLAY 0.872340 (-2925 3575);
DISPLAY INVISIBLE (-2925 3575);
FORCEPROP 1 LAST PATH I204
J 0
(-3252 3700);
DISPLAY 0.872340 (-3252 3700);
PAINT GREEN (-3252 3700);
DISPLAY INVISIBLE (-3252 3700);
FORCEADD TAP..1
(-3250 3650);
FORCEPROP 3 LASTPIN (-3300 3650) SIG_NAME M_J_CPU0_SB_DQ<10>
J 0
(-3290 3660);
DISPLAY 0.659574 (-3290 3660);
PAINT MONO (-3290 3660);
DISPLAY INVISIBLE (-3290 3660);
FORCEPROP 1 LASTPIN (-3300 3650) BN 10
J 0
(-3312 3658);
DISPLAY 0.489362 (-3312 3658);
PAINT GREEN (-3312 3658);
FORCEPROP 2 LAST CDS_LIB mstr_standard
J 0
(-3250 3650);
DISPLAY 0.723404 (-3250 3650);
PAINT MONO (-3250 3650);
DISPLAY INVISIBLE (-3250 3650);
FORCEPROP 1 LAST BODY_TYPE PLUMBING
J 0
(-3250 3700);
DISPLAY 0.872340 (-3250 3700);
PAINT GREEN (-3250 3700);
DISPLAY INVISIBLE (-3250 3700);
FORCEPROP 1 LAST HDL_TAP TRUE
J 0
(-2925 3525);
DISPLAY 0.872340 (-2925 3525);
DISPLAY INVISIBLE (-2925 3525);
FORCEPROP 1 LAST PATH I205
J 0
(-3252 3650);
DISPLAY 0.872340 (-3252 3650);
PAINT GREEN (-3252 3650);
DISPLAY INVISIBLE (-3252 3650);
FORCEADD TAP..1
(-3250 3600);
FORCEPROP 3 LASTPIN (-3300 3600) SIG_NAME M_J_CPU0_SB_DQ<11>
J 0
(-3290 3610);
DISPLAY 0.659574 (-3290 3610);
PAINT MONO (-3290 3610);
DISPLAY INVISIBLE (-3290 3610);
FORCEPROP 1 LASTPIN (-3300 3600) BN 11
J 0
(-3312 3608);
DISPLAY 0.489362 (-3312 3608);
PAINT GREEN (-3312 3608);
FORCEPROP 2 LAST CDS_LIB mstr_standard
J 0
(-3250 3600);
DISPLAY 0.723404 (-3250 3600);
PAINT MONO (-3250 3600);
DISPLAY INVISIBLE (-3250 3600);
FORCEPROP 1 LAST BODY_TYPE PLUMBING
J 0
(-3250 3650);
DISPLAY 0.872340 (-3250 3650);
PAINT GREEN (-3250 3650);
DISPLAY INVISIBLE (-3250 3650);
FORCEPROP 1 LAST HDL_TAP TRUE
J 0
(-2925 3475);
DISPLAY 0.872340 (-2925 3475);
DISPLAY INVISIBLE (-2925 3475);
FORCEPROP 1 LAST PATH I206
J 0
(-3252 3600);
DISPLAY 0.872340 (-3252 3600);
PAINT GREEN (-3252 3600);
DISPLAY INVISIBLE (-3252 3600);
FORCEADD TAP..1
(-3250 3500);
FORCEPROP 3 LASTPIN (-3300 3500) SIG_NAME M_J_CPU0_SB_DQ<13>
J 0
(-3290 3510);
DISPLAY 0.659574 (-3290 3510);
PAINT MONO (-3290 3510);
DISPLAY INVISIBLE (-3290 3510);
FORCEPROP 1 LASTPIN (-3300 3500) BN 13
J 0
(-3312 3508);
DISPLAY 0.489362 (-3312 3508);
PAINT GREEN (-3312 3508);
FORCEPROP 2 LAST CDS_LIB mstr_standard
J 0
(-3250 3500);
DISPLAY 0.723404 (-3250 3500);
PAINT MONO (-3250 3500);
DISPLAY INVISIBLE (-3250 3500);
FORCEPROP 1 LAST BODY_TYPE PLUMBING
J 0
(-3250 3550);
DISPLAY 0.872340 (-3250 3550);
PAINT GREEN (-3250 3550);
DISPLAY INVISIBLE (-3250 3550);
FORCEPROP 1 LAST HDL_TAP TRUE
J 0
(-2925 3375);
DISPLAY 0.872340 (-2925 3375);
DISPLAY INVISIBLE (-2925 3375);
FORCEPROP 1 LAST PATH I207
J 0
(-3252 3500);
DISPLAY 0.872340 (-3252 3500);
PAINT GREEN (-3252 3500);
DISPLAY INVISIBLE (-3252 3500);
FORCEADD TAP..1
(-3250 3550);
FORCEPROP 3 LASTPIN (-3300 3550) SIG_NAME M_J_CPU0_SB_DQ<12>
J 0
(-3290 3560);
DISPLAY 0.659574 (-3290 3560);
PAINT MONO (-3290 3560);
DISPLAY INVISIBLE (-3290 3560);
FORCEPROP 1 LASTPIN (-3300 3550) BN 12
J 0
(-3312 3558);
DISPLAY 0.489362 (-3312 3558);
PAINT GREEN (-3312 3558);
FORCEPROP 2 LAST CDS_LIB mstr_standard
J 0
(-3250 3550);
DISPLAY 0.723404 (-3250 3550);
PAINT MONO (-3250 3550);
DISPLAY INVISIBLE (-3250 3550);
FORCEPROP 1 LAST BODY_TYPE PLUMBING
J 0
(-3250 3600);
DISPLAY 0.872340 (-3250 3600);
PAINT GREEN (-3250 3600);
DISPLAY INVISIBLE (-3250 3600);
FORCEPROP 1 LAST HDL_TAP TRUE
J 0
(-2925 3425);
DISPLAY 0.872340 (-2925 3425);
DISPLAY INVISIBLE (-2925 3425);
FORCEPROP 1 LAST PATH I208
J 0
(-3252 3550);
DISPLAY 0.872340 (-3252 3550);
PAINT GREEN (-3252 3550);
DISPLAY INVISIBLE (-3252 3550);
FORCEADD TAP..1
(-3250 3400);
FORCEPROP 3 LASTPIN (-3300 3400) SIG_NAME M_J_CPU0_SB_DQ<15>
J 0
(-3290 3410);
DISPLAY 0.659574 (-3290 3410);
PAINT MONO (-3290 3410);
DISPLAY INVISIBLE (-3290 3410);
FORCEPROP 1 LASTPIN (-3300 3400) BN 15
J 0
(-3312 3408);
DISPLAY 0.489362 (-3312 3408);
PAINT GREEN (-3312 3408);
FORCEPROP 2 LAST CDS_LIB mstr_standard
J 0
(-3250 3400);
DISPLAY 0.723404 (-3250 3400);
PAINT MONO (-3250 3400);
DISPLAY INVISIBLE (-3250 3400);
FORCEPROP 1 LAST BODY_TYPE PLUMBING
J 0
(-3250 3450);
DISPLAY 0.872340 (-3250 3450);
PAINT GREEN (-3250 3450);
DISPLAY INVISIBLE (-3250 3450);
FORCEPROP 1 LAST HDL_TAP TRUE
J 0
(-2925 3275);
DISPLAY 0.872340 (-2925 3275);
DISPLAY INVISIBLE (-2925 3275);
FORCEPROP 1 LAST PATH I209
J 0
(-3252 3400);
DISPLAY 0.872340 (-3252 3400);
PAINT GREEN (-3252 3400);
DISPLAY INVISIBLE (-3252 3400);
FORCEADD TAP..1
(-3250 3450);
FORCEPROP 3 LASTPIN (-3300 3450) SIG_NAME M_J_CPU0_SB_DQ<14>
J 0
(-3290 3460);
DISPLAY 0.659574 (-3290 3460);
PAINT MONO (-3290 3460);
DISPLAY INVISIBLE (-3290 3460);
FORCEPROP 1 LASTPIN (-3300 3450) BN 14
J 0
(-3312 3458);
DISPLAY 0.489362 (-3312 3458);
PAINT GREEN (-3312 3458);
FORCEPROP 2 LAST CDS_LIB mstr_standard
J 0
(-3250 3450);
DISPLAY 0.723404 (-3250 3450);
PAINT MONO (-3250 3450);
DISPLAY INVISIBLE (-3250 3450);
FORCEPROP 1 LAST BODY_TYPE PLUMBING
J 0
(-3250 3500);
DISPLAY 0.872340 (-3250 3500);
PAINT GREEN (-3250 3500);
DISPLAY INVISIBLE (-3250 3500);
FORCEPROP 1 LAST HDL_TAP TRUE
J 0
(-2925 3325);
DISPLAY 0.872340 (-2925 3325);
DISPLAY INVISIBLE (-2925 3325);
FORCEPROP 1 LAST PATH I210
J 0
(-3252 3450);
DISPLAY 0.872340 (-3252 3450);
PAINT GREEN (-3252 3450);
DISPLAY INVISIBLE (-3252 3450);
FORCEADD TAP..1
(-3250 3250);
FORCEPROP 3 LASTPIN (-3300 3250) SIG_NAME M_J_CPU0_SB_DQ<17>
J 0
(-3290 3260);
DISPLAY 0.659574 (-3290 3260);
PAINT MONO (-3290 3260);
DISPLAY INVISIBLE (-3290 3260);
FORCEPROP 1 LASTPIN (-3300 3250) BN 17
J 0
(-3312 3258);
DISPLAY 0.489362 (-3312 3258);
PAINT GREEN (-3312 3258);
FORCEPROP 2 LAST CDS_LIB mstr_standard
J 0
(-3250 3250);
DISPLAY 0.723404 (-3250 3250);
PAINT MONO (-3250 3250);
DISPLAY INVISIBLE (-3250 3250);
FORCEPROP 1 LAST BODY_TYPE PLUMBING
J 0
(-3250 3300);
DISPLAY 0.872340 (-3250 3300);
PAINT GREEN (-3250 3300);
DISPLAY INVISIBLE (-3250 3300);
FORCEPROP 1 LAST HDL_TAP TRUE
J 0
(-2925 3125);
DISPLAY 0.872340 (-2925 3125);
DISPLAY INVISIBLE (-2925 3125);
FORCEPROP 1 LAST PATH I211
J 0
(-3252 3250);
DISPLAY 0.872340 (-3252 3250);
PAINT GREEN (-3252 3250);
DISPLAY INVISIBLE (-3252 3250);
FORCEADD TAP..1
(-3250 3300);
FORCEPROP 3 LASTPIN (-3300 3300) SIG_NAME M_J_CPU0_SB_DQ<16>
J 0
(-3290 3310);
DISPLAY 0.659574 (-3290 3310);
PAINT MONO (-3290 3310);
DISPLAY INVISIBLE (-3290 3310);
FORCEPROP 1 LASTPIN (-3300 3300) BN 16
J 0
(-3312 3308);
DISPLAY 0.489362 (-3312 3308);
PAINT GREEN (-3312 3308);
FORCEPROP 2 LAST CDS_LIB mstr_standard
J 0
(-3250 3300);
DISPLAY 0.723404 (-3250 3300);
PAINT MONO (-3250 3300);
DISPLAY INVISIBLE (-3250 3300);
FORCEPROP 1 LAST BODY_TYPE PLUMBING
J 0
(-3250 3350);
DISPLAY 0.872340 (-3250 3350);
PAINT GREEN (-3250 3350);
DISPLAY INVISIBLE (-3250 3350);
FORCEPROP 1 LAST HDL_TAP TRUE
J 0
(-2925 3175);
DISPLAY 0.872340 (-2925 3175);
DISPLAY INVISIBLE (-2925 3175);
FORCEPROP 1 LAST PATH I212
J 0
(-3252 3300);
DISPLAY 0.872340 (-3252 3300);
PAINT GREEN (-3252 3300);
DISPLAY INVISIBLE (-3252 3300);
FORCEADD TAP..1
(-3250 3200);
FORCEPROP 3 LASTPIN (-3300 3200) SIG_NAME M_J_CPU0_SB_DQ<18>
J 0
(-3290 3210);
DISPLAY 0.659574 (-3290 3210);
PAINT MONO (-3290 3210);
DISPLAY INVISIBLE (-3290 3210);
FORCEPROP 1 LASTPIN (-3300 3200) BN 18
J 0
(-3312 3208);
DISPLAY 0.489362 (-3312 3208);
PAINT GREEN (-3312 3208);
FORCEPROP 2 LAST CDS_LIB mstr_standard
J 0
(-3250 3200);
DISPLAY 0.723404 (-3250 3200);
PAINT MONO (-3250 3200);
DISPLAY INVISIBLE (-3250 3200);
FORCEPROP 1 LAST BODY_TYPE PLUMBING
J 0
(-3250 3250);
DISPLAY 0.872340 (-3250 3250);
PAINT GREEN (-3250 3250);
DISPLAY INVISIBLE (-3250 3250);
FORCEPROP 1 LAST HDL_TAP TRUE
J 0
(-2925 3075);
DISPLAY 0.872340 (-2925 3075);
DISPLAY INVISIBLE (-2925 3075);
FORCEPROP 1 LAST PATH I213
J 0
(-3252 3200);
DISPLAY 0.872340 (-3252 3200);
PAINT GREEN (-3252 3200);
DISPLAY INVISIBLE (-3252 3200);
FORCEADD TAP..1
(-3250 3100);
FORCEPROP 3 LASTPIN (-3300 3100) SIG_NAME M_J_CPU0_SB_DQ<20>
J 0
(-3290 3110);
DISPLAY 0.659574 (-3290 3110);
PAINT MONO (-3290 3110);
DISPLAY INVISIBLE (-3290 3110);
FORCEPROP 1 LASTPIN (-3300 3100) BN 20
J 0
(-3312 3108);
DISPLAY 0.489362 (-3312 3108);
PAINT GREEN (-3312 3108);
FORCEPROP 2 LAST CDS_LIB mstr_standard
J 0
(-3250 3100);
DISPLAY 0.723404 (-3250 3100);
PAINT MONO (-3250 3100);
DISPLAY INVISIBLE (-3250 3100);
FORCEPROP 1 LAST BODY_TYPE PLUMBING
J 0
(-3250 3150);
DISPLAY 0.872340 (-3250 3150);
PAINT GREEN (-3250 3150);
DISPLAY INVISIBLE (-3250 3150);
FORCEPROP 1 LAST HDL_TAP TRUE
J 0
(-2925 2975);
DISPLAY 0.872340 (-2925 2975);
DISPLAY INVISIBLE (-2925 2975);
FORCEPROP 1 LAST PATH I214
J 0
(-3252 3100);
DISPLAY 0.872340 (-3252 3100);
PAINT GREEN (-3252 3100);
DISPLAY INVISIBLE (-3252 3100);
FORCEADD TAP..1
(-3250 3150);
FORCEPROP 3 LASTPIN (-3300 3150) SIG_NAME M_J_CPU0_SB_DQ<19>
J 0
(-3290 3160);
DISPLAY 0.659574 (-3290 3160);
PAINT MONO (-3290 3160);
DISPLAY INVISIBLE (-3290 3160);
FORCEPROP 1 LASTPIN (-3300 3150) BN 19
J 0
(-3312 3158);
DISPLAY 0.489362 (-3312 3158);
PAINT GREEN (-3312 3158);
FORCEPROP 2 LAST CDS_LIB mstr_standard
J 0
(-3250 3150);
DISPLAY 0.723404 (-3250 3150);
PAINT MONO (-3250 3150);
DISPLAY INVISIBLE (-3250 3150);
FORCEPROP 1 LAST BODY_TYPE PLUMBING
J 0
(-3250 3200);
DISPLAY 0.872340 (-3250 3200);
PAINT GREEN (-3250 3200);
DISPLAY INVISIBLE (-3250 3200);
FORCEPROP 1 LAST HDL_TAP TRUE
J 0
(-2925 3025);
DISPLAY 0.872340 (-2925 3025);
DISPLAY INVISIBLE (-2925 3025);
FORCEPROP 1 LAST PATH I215
J 0
(-3252 3150);
DISPLAY 0.872340 (-3252 3150);
PAINT GREEN (-3252 3150);
DISPLAY INVISIBLE (-3252 3150);
FORCEADD TAP..1
(-3250 2950);
FORCEPROP 3 LASTPIN (-3300 2950) SIG_NAME M_J_CPU0_SB_DQ<23>
J 0
(-3290 2960);
DISPLAY 0.659574 (-3290 2960);
PAINT MONO (-3290 2960);
DISPLAY INVISIBLE (-3290 2960);
FORCEPROP 1 LASTPIN (-3300 2950) BN 23
J 0
(-3312 2958);
DISPLAY 0.489362 (-3312 2958);
PAINT GREEN (-3312 2958);
FORCEPROP 2 LAST CDS_LIB mstr_standard
J 0
(-3250 2950);
DISPLAY 0.723404 (-3250 2950);
PAINT MONO (-3250 2950);
DISPLAY INVISIBLE (-3250 2950);
FORCEPROP 1 LAST BODY_TYPE PLUMBING
J 0
(-3250 3000);
DISPLAY 0.872340 (-3250 3000);
PAINT GREEN (-3250 3000);
DISPLAY INVISIBLE (-3250 3000);
FORCEPROP 1 LAST HDL_TAP TRUE
J 0
(-2925 2825);
DISPLAY 0.872340 (-2925 2825);
DISPLAY INVISIBLE (-2925 2825);
FORCEPROP 1 LAST PATH I216
J 0
(-3252 2950);
DISPLAY 0.872340 (-3252 2950);
PAINT GREEN (-3252 2950);
DISPLAY INVISIBLE (-3252 2950);
FORCEADD TAP..1
(-3250 3000);
FORCEPROP 3 LASTPIN (-3300 3000) SIG_NAME M_J_CPU0_SB_DQ<22>
J 0
(-3290 3010);
DISPLAY 0.659574 (-3290 3010);
PAINT MONO (-3290 3010);
DISPLAY INVISIBLE (-3290 3010);
FORCEPROP 1 LASTPIN (-3300 3000) BN 22
J 0
(-3312 3008);
DISPLAY 0.489362 (-3312 3008);
PAINT GREEN (-3312 3008);
FORCEPROP 2 LAST CDS_LIB mstr_standard
J 0
(-3250 3000);
DISPLAY 0.723404 (-3250 3000);
PAINT MONO (-3250 3000);
DISPLAY INVISIBLE (-3250 3000);
FORCEPROP 1 LAST BODY_TYPE PLUMBING
J 0
(-3250 3050);
DISPLAY 0.872340 (-3250 3050);
PAINT GREEN (-3250 3050);
DISPLAY INVISIBLE (-3250 3050);
FORCEPROP 1 LAST HDL_TAP TRUE
J 0
(-2925 2875);
DISPLAY 0.872340 (-2925 2875);
DISPLAY INVISIBLE (-2925 2875);
FORCEPROP 1 LAST PATH I217
J 0
(-3252 3000);
DISPLAY 0.872340 (-3252 3000);
PAINT GREEN (-3252 3000);
DISPLAY INVISIBLE (-3252 3000);
FORCEADD TAP..1
(-3250 3050);
FORCEPROP 3 LASTPIN (-3300 3050) SIG_NAME M_J_CPU0_SB_DQ<21>
J 0
(-3290 3060);
DISPLAY 0.659574 (-3290 3060);
PAINT MONO (-3290 3060);
DISPLAY INVISIBLE (-3290 3060);
FORCEPROP 1 LASTPIN (-3300 3050) BN 21
J 0
(-3312 3058);
DISPLAY 0.489362 (-3312 3058);
PAINT GREEN (-3312 3058);
FORCEPROP 2 LAST CDS_LIB mstr_standard
J 0
(-3250 3050);
DISPLAY 0.723404 (-3250 3050);
PAINT MONO (-3250 3050);
DISPLAY INVISIBLE (-3250 3050);
FORCEPROP 1 LAST BODY_TYPE PLUMBING
J 0
(-3250 3100);
DISPLAY 0.872340 (-3250 3100);
PAINT GREEN (-3250 3100);
DISPLAY INVISIBLE (-3250 3100);
FORCEPROP 1 LAST HDL_TAP TRUE
J 0
(-2925 2925);
DISPLAY 0.872340 (-2925 2925);
DISPLAY INVISIBLE (-2925 2925);
FORCEPROP 1 LAST PATH I218
J 0
(-3252 3050);
DISPLAY 0.872340 (-3252 3050);
PAINT GREEN (-3252 3050);
DISPLAY INVISIBLE (-3252 3050);
FORCEADD TAP..1
(-3250 2850);
FORCEPROP 3 LASTPIN (-3300 2850) SIG_NAME M_J_CPU0_SB_DQ<24>
J 0
(-3290 2860);
DISPLAY 0.659574 (-3290 2860);
PAINT MONO (-3290 2860);
DISPLAY INVISIBLE (-3290 2860);
FORCEPROP 1 LASTPIN (-3300 2850) BN 24
J 0
(-3312 2858);
DISPLAY 0.489362 (-3312 2858);
PAINT GREEN (-3312 2858);
FORCEPROP 2 LAST CDS_LIB mstr_standard
J 0
(-3250 2850);
DISPLAY 0.723404 (-3250 2850);
PAINT MONO (-3250 2850);
DISPLAY INVISIBLE (-3250 2850);
FORCEPROP 1 LAST BODY_TYPE PLUMBING
J 0
(-3250 2900);
DISPLAY 0.872340 (-3250 2900);
PAINT GREEN (-3250 2900);
DISPLAY INVISIBLE (-3250 2900);
FORCEPROP 1 LAST HDL_TAP TRUE
J 0
(-2925 2725);
DISPLAY 0.872340 (-2925 2725);
DISPLAY INVISIBLE (-2925 2725);
FORCEPROP 1 LAST PATH I219
J 0
(-3252 2850);
DISPLAY 0.872340 (-3252 2850);
PAINT GREEN (-3252 2850);
DISPLAY INVISIBLE (-3252 2850);
FORCEADD TAP..1
(-3250 2800);
FORCEPROP 3 LASTPIN (-3300 2800) SIG_NAME M_J_CPU0_SB_DQ<25>
J 0
(-3290 2810);
DISPLAY 0.659574 (-3290 2810);
PAINT MONO (-3290 2810);
DISPLAY INVISIBLE (-3290 2810);
FORCEPROP 1 LASTPIN (-3300 2800) BN 25
J 0
(-3312 2808);
DISPLAY 0.489362 (-3312 2808);
PAINT GREEN (-3312 2808);
FORCEPROP 2 LAST CDS_LIB mstr_standard
J 0
(-3250 2800);
DISPLAY 0.723404 (-3250 2800);
PAINT MONO (-3250 2800);
DISPLAY INVISIBLE (-3250 2800);
FORCEPROP 1 LAST BODY_TYPE PLUMBING
J 0
(-3250 2850);
DISPLAY 0.872340 (-3250 2850);
PAINT GREEN (-3250 2850);
DISPLAY INVISIBLE (-3250 2850);
FORCEPROP 1 LAST HDL_TAP TRUE
J 0
(-2925 2675);
DISPLAY 0.872340 (-2925 2675);
DISPLAY INVISIBLE (-2925 2675);
FORCEPROP 1 LAST PATH I220
J 0
(-3252 2800);
DISPLAY 0.872340 (-3252 2800);
PAINT GREEN (-3252 2800);
DISPLAY INVISIBLE (-3252 2800);
FORCEADD TAP..1
(-3250 2750);
FORCEPROP 3 LASTPIN (-3300 2750) SIG_NAME M_J_CPU0_SB_DQ<26>
J 0
(-3290 2760);
DISPLAY 0.659574 (-3290 2760);
PAINT MONO (-3290 2760);
DISPLAY INVISIBLE (-3290 2760);
FORCEPROP 1 LASTPIN (-3300 2750) BN 26
J 0
(-3312 2758);
DISPLAY 0.489362 (-3312 2758);
PAINT GREEN (-3312 2758);
FORCEPROP 2 LAST CDS_LIB mstr_standard
J 0
(-3250 2750);
DISPLAY 0.723404 (-3250 2750);
PAINT MONO (-3250 2750);
DISPLAY INVISIBLE (-3250 2750);
FORCEPROP 1 LAST BODY_TYPE PLUMBING
J 0
(-3250 2800);
DISPLAY 0.872340 (-3250 2800);
PAINT GREEN (-3250 2800);
DISPLAY INVISIBLE (-3250 2800);
FORCEPROP 1 LAST HDL_TAP TRUE
J 0
(-2925 2625);
DISPLAY 0.872340 (-2925 2625);
DISPLAY INVISIBLE (-2925 2625);
FORCEPROP 1 LAST PATH I221
J 0
(-3252 2750);
DISPLAY 0.872340 (-3252 2750);
PAINT GREEN (-3252 2750);
DISPLAY INVISIBLE (-3252 2750);
FORCEADD TAP..1
(-3250 2700);
FORCEPROP 3 LASTPIN (-3300 2700) SIG_NAME M_J_CPU0_SB_DQ<27>
J 0
(-3290 2710);
DISPLAY 0.659574 (-3290 2710);
PAINT MONO (-3290 2710);
DISPLAY INVISIBLE (-3290 2710);
FORCEPROP 1 LASTPIN (-3300 2700) BN 27
J 0
(-3312 2708);
DISPLAY 0.489362 (-3312 2708);
PAINT GREEN (-3312 2708);
FORCEPROP 2 LAST CDS_LIB mstr_standard
J 0
(-3250 2700);
DISPLAY 0.723404 (-3250 2700);
PAINT MONO (-3250 2700);
DISPLAY INVISIBLE (-3250 2700);
FORCEPROP 1 LAST BODY_TYPE PLUMBING
J 0
(-3250 2750);
DISPLAY 0.872340 (-3250 2750);
PAINT GREEN (-3250 2750);
DISPLAY INVISIBLE (-3250 2750);
FORCEPROP 1 LAST HDL_TAP TRUE
J 0
(-2925 2575);
DISPLAY 0.872340 (-2925 2575);
DISPLAY INVISIBLE (-2925 2575);
FORCEPROP 1 LAST PATH I222
J 0
(-3252 2700);
DISPLAY 0.872340 (-3252 2700);
PAINT GREEN (-3252 2700);
DISPLAY INVISIBLE (-3252 2700);
FORCEADD TAP..1
(-3250 2650);
FORCEPROP 3 LASTPIN (-3300 2650) SIG_NAME M_J_CPU0_SB_DQ<28>
J 0
(-3290 2660);
DISPLAY 0.659574 (-3290 2660);
PAINT MONO (-3290 2660);
DISPLAY INVISIBLE (-3290 2660);
FORCEPROP 1 LASTPIN (-3300 2650) BN 28
J 0
(-3312 2658);
DISPLAY 0.489362 (-3312 2658);
PAINT GREEN (-3312 2658);
FORCEPROP 2 LAST CDS_LIB mstr_standard
J 0
(-3250 2650);
DISPLAY 0.723404 (-3250 2650);
PAINT MONO (-3250 2650);
DISPLAY INVISIBLE (-3250 2650);
FORCEPROP 1 LAST BODY_TYPE PLUMBING
J 0
(-3250 2700);
DISPLAY 0.872340 (-3250 2700);
PAINT GREEN (-3250 2700);
DISPLAY INVISIBLE (-3250 2700);
FORCEPROP 1 LAST HDL_TAP TRUE
J 0
(-2925 2525);
DISPLAY 0.872340 (-2925 2525);
DISPLAY INVISIBLE (-2925 2525);
FORCEPROP 1 LAST PATH I223
J 0
(-3252 2650);
DISPLAY 0.872340 (-3252 2650);
PAINT GREEN (-3252 2650);
DISPLAY INVISIBLE (-3252 2650);
FORCEADD TAP..1
(-3250 2600);
FORCEPROP 3 LASTPIN (-3300 2600) SIG_NAME M_J_CPU0_SB_DQ<29>
J 0
(-3290 2610);
DISPLAY 0.659574 (-3290 2610);
PAINT MONO (-3290 2610);
DISPLAY INVISIBLE (-3290 2610);
FORCEPROP 1 LASTPIN (-3300 2600) BN 29
J 0
(-3312 2608);
DISPLAY 0.489362 (-3312 2608);
PAINT GREEN (-3312 2608);
FORCEPROP 2 LAST CDS_LIB mstr_standard
J 0
(-3250 2600);
DISPLAY 0.723404 (-3250 2600);
PAINT MONO (-3250 2600);
DISPLAY INVISIBLE (-3250 2600);
FORCEPROP 1 LAST BODY_TYPE PLUMBING
J 0
(-3250 2650);
DISPLAY 0.872340 (-3250 2650);
PAINT GREEN (-3250 2650);
DISPLAY INVISIBLE (-3250 2650);
FORCEPROP 1 LAST HDL_TAP TRUE
J 0
(-2925 2475);
DISPLAY 0.872340 (-2925 2475);
DISPLAY INVISIBLE (-2925 2475);
FORCEPROP 1 LAST PATH I224
J 0
(-3252 2600);
DISPLAY 0.872340 (-3252 2600);
PAINT GREEN (-3252 2600);
DISPLAY INVISIBLE (-3252 2600);
FORCEADD TAP..1
(-3250 2550);
FORCEPROP 3 LASTPIN (-3300 2550) SIG_NAME M_J_CPU0_SB_DQ<30>
J 0
(-3290 2560);
DISPLAY 0.659574 (-3290 2560);
PAINT MONO (-3290 2560);
DISPLAY INVISIBLE (-3290 2560);
FORCEPROP 1 LASTPIN (-3300 2550) BN 30
J 0
(-3312 2558);
DISPLAY 0.489362 (-3312 2558);
PAINT GREEN (-3312 2558);
FORCEPROP 2 LAST CDS_LIB mstr_standard
J 0
(-3250 2550);
DISPLAY 0.723404 (-3250 2550);
PAINT MONO (-3250 2550);
DISPLAY INVISIBLE (-3250 2550);
FORCEPROP 1 LAST BODY_TYPE PLUMBING
J 0
(-3250 2600);
DISPLAY 0.872340 (-3250 2600);
PAINT GREEN (-3250 2600);
DISPLAY INVISIBLE (-3250 2600);
FORCEPROP 1 LAST HDL_TAP TRUE
J 0
(-2925 2425);
DISPLAY 0.872340 (-2925 2425);
DISPLAY INVISIBLE (-2925 2425);
FORCEPROP 1 LAST PATH I225
J 0
(-3252 2550);
DISPLAY 0.872340 (-3252 2550);
PAINT GREEN (-3252 2550);
DISPLAY INVISIBLE (-3252 2550);
FORCEADD TAP..1
(-3250 2500);
FORCEPROP 3 LASTPIN (-3300 2500) SIG_NAME M_J_CPU0_SB_DQ<31>
J 0
(-3290 2510);
DISPLAY 0.659574 (-3290 2510);
PAINT MONO (-3290 2510);
DISPLAY INVISIBLE (-3290 2510);
FORCEPROP 1 LASTPIN (-3300 2500) BN 31
J 0
(-3312 2508);
DISPLAY 0.489362 (-3312 2508);
PAINT GREEN (-3312 2508);
FORCEPROP 2 LAST CDS_LIB mstr_standard
J 0
(-3250 2500);
DISPLAY 0.723404 (-3250 2500);
PAINT MONO (-3250 2500);
DISPLAY INVISIBLE (-3250 2500);
FORCEPROP 1 LAST BODY_TYPE PLUMBING
J 0
(-3250 2550);
DISPLAY 0.872340 (-3250 2550);
PAINT GREEN (-3250 2550);
DISPLAY INVISIBLE (-3250 2550);
FORCEPROP 1 LAST HDL_TAP TRUE
J 0
(-2925 2375);
DISPLAY 0.872340 (-2925 2375);
DISPLAY INVISIBLE (-2925 2375);
FORCEPROP 1 LAST PATH I226
J 0
(-3252 2500);
DISPLAY 0.872340 (-3252 2500);
PAINT GREEN (-3252 2500);
DISPLAY INVISIBLE (-3252 2500);
FORCEADD TAP..1
(-3250 2400);
FORCEPROP 3 LASTPIN (-3300 2400) SIG_NAME M_J_CPU0_SA_CB<0>
J 0
(-3290 2410);
DISPLAY 0.659574 (-3290 2410);
PAINT MONO (-3290 2410);
DISPLAY INVISIBLE (-3290 2410);
FORCEPROP 1 LASTPIN (-3300 2400) BN 0
J 0
(-3312 2408);
DISPLAY 0.489362 (-3312 2408);
PAINT GREEN (-3312 2408);
FORCEPROP 2 LAST CDS_LIB mstr_standard
J 2
(-3250 2400);
DISPLAY 0.723404 (-3250 2400);
PAINT MONO (-3250 2400);
DISPLAY INVISIBLE (-3250 2400);
FORCEPROP 1 LAST BODY_TYPE PLUMBING
J 0
(-3250 2450);
DISPLAY 0.872340 (-3250 2450);
PAINT GREEN (-3250 2450);
DISPLAY INVISIBLE (-3250 2450);
FORCEPROP 1 LAST HDL_TAP TRUE
J 0
(-2925 2275);
DISPLAY 0.872340 (-2925 2275);
DISPLAY INVISIBLE (-2925 2275);
FORCEPROP 1 LAST PATH I227
J 0
(-3252 2400);
DISPLAY 0.872340 (-3252 2400);
PAINT GREEN (-3252 2400);
DISPLAY INVISIBLE (-3252 2400);
FORCEADD TAP..1
(-3250 2350);
FORCEPROP 3 LASTPIN (-3300 2350) SIG_NAME M_J_CPU0_SA_CB<1>
J 0
(-3290 2360);
DISPLAY 0.659574 (-3290 2360);
PAINT MONO (-3290 2360);
DISPLAY INVISIBLE (-3290 2360);
FORCEPROP 1 LASTPIN (-3300 2350) BN 1
J 0
(-3312 2358);
DISPLAY 0.489362 (-3312 2358);
PAINT GREEN (-3312 2358);
FORCEPROP 2 LAST CDS_LIB mstr_standard
J 2
(-3250 2350);
DISPLAY 0.723404 (-3250 2350);
PAINT MONO (-3250 2350);
DISPLAY INVISIBLE (-3250 2350);
FORCEPROP 1 LAST BODY_TYPE PLUMBING
J 0
(-3250 2400);
DISPLAY 0.872340 (-3250 2400);
PAINT GREEN (-3250 2400);
DISPLAY INVISIBLE (-3250 2400);
FORCEPROP 1 LAST HDL_TAP TRUE
J 0
(-2925 2225);
DISPLAY 0.872340 (-2925 2225);
DISPLAY INVISIBLE (-2925 2225);
FORCEPROP 1 LAST PATH I228
J 0
(-3252 2350);
DISPLAY 0.872340 (-3252 2350);
PAINT GREEN (-3252 2350);
DISPLAY INVISIBLE (-3252 2350);
FORCEADD TAP..1
(-3250 2300);
FORCEPROP 3 LASTPIN (-3300 2300) SIG_NAME M_J_CPU0_SA_CB<2>
J 0
(-3290 2310);
DISPLAY 0.659574 (-3290 2310);
PAINT MONO (-3290 2310);
DISPLAY INVISIBLE (-3290 2310);
FORCEPROP 1 LASTPIN (-3300 2300) BN 2
J 0
(-3312 2308);
DISPLAY 0.489362 (-3312 2308);
PAINT GREEN (-3312 2308);
FORCEPROP 2 LAST CDS_LIB mstr_standard
J 2
(-3250 2300);
DISPLAY 0.723404 (-3250 2300);
PAINT MONO (-3250 2300);
DISPLAY INVISIBLE (-3250 2300);
FORCEPROP 1 LAST BODY_TYPE PLUMBING
J 0
(-3250 2350);
DISPLAY 0.872340 (-3250 2350);
PAINT GREEN (-3250 2350);
DISPLAY INVISIBLE (-3250 2350);
FORCEPROP 1 LAST HDL_TAP TRUE
J 0
(-2925 2175);
DISPLAY 0.872340 (-2925 2175);
DISPLAY INVISIBLE (-2925 2175);
FORCEPROP 1 LAST PATH I229
J 0
(-3252 2300);
DISPLAY 0.872340 (-3252 2300);
PAINT GREEN (-3252 2300);
DISPLAY INVISIBLE (-3252 2300);
FORCEADD TAP..1
(-3250 2250);
FORCEPROP 3 LASTPIN (-3300 2250) SIG_NAME M_J_CPU0_SA_CB<3>
J 0
(-3290 2260);
DISPLAY 0.659574 (-3290 2260);
PAINT MONO (-3290 2260);
DISPLAY INVISIBLE (-3290 2260);
FORCEPROP 1 LASTPIN (-3300 2250) BN 3
J 0
(-3312 2258);
DISPLAY 0.489362 (-3312 2258);
PAINT GREEN (-3312 2258);
FORCEPROP 2 LAST CDS_LIB mstr_standard
J 2
(-3250 2250);
DISPLAY 0.723404 (-3250 2250);
PAINT MONO (-3250 2250);
DISPLAY INVISIBLE (-3250 2250);
FORCEPROP 1 LAST BODY_TYPE PLUMBING
J 0
(-3250 2300);
DISPLAY 0.872340 (-3250 2300);
PAINT GREEN (-3250 2300);
DISPLAY INVISIBLE (-3250 2300);
FORCEPROP 1 LAST HDL_TAP TRUE
J 0
(-2925 2125);
DISPLAY 0.872340 (-2925 2125);
DISPLAY INVISIBLE (-2925 2125);
FORCEPROP 1 LAST PATH I230
J 0
(-3252 2250);
DISPLAY 0.872340 (-3252 2250);
PAINT GREEN (-3252 2250);
DISPLAY INVISIBLE (-3252 2250);
FORCEADD TAP..1
(-3250 2200);
FORCEPROP 3 LASTPIN (-3300 2200) SIG_NAME M_J_CPU0_SA_CB<4>
J 0
(-3290 2210);
DISPLAY 0.659574 (-3290 2210);
PAINT MONO (-3290 2210);
DISPLAY INVISIBLE (-3290 2210);
FORCEPROP 1 LASTPIN (-3300 2200) BN 4
J 0
(-3312 2208);
DISPLAY 0.489362 (-3312 2208);
PAINT GREEN (-3312 2208);
FORCEPROP 2 LAST CDS_LIB mstr_standard
J 2
(-3250 2200);
DISPLAY 0.723404 (-3250 2200);
PAINT MONO (-3250 2200);
DISPLAY INVISIBLE (-3250 2200);
FORCEPROP 1 LAST BODY_TYPE PLUMBING
J 0
(-3250 2250);
DISPLAY 0.872340 (-3250 2250);
PAINT GREEN (-3250 2250);
DISPLAY INVISIBLE (-3250 2250);
FORCEPROP 1 LAST HDL_TAP TRUE
J 0
(-2925 2075);
DISPLAY 0.872340 (-2925 2075);
DISPLAY INVISIBLE (-2925 2075);
FORCEPROP 1 LAST PATH I231
J 0
(-3252 2200);
DISPLAY 0.872340 (-3252 2200);
PAINT GREEN (-3252 2200);
DISPLAY INVISIBLE (-3252 2200);
FORCEADD TAP..1
(-3250 2100);
FORCEPROP 3 LASTPIN (-3300 2100) SIG_NAME M_J_CPU0_SA_CB<6>
J 0
(-3290 2110);
DISPLAY 0.659574 (-3290 2110);
PAINT MONO (-3290 2110);
DISPLAY INVISIBLE (-3290 2110);
FORCEPROP 1 LASTPIN (-3300 2100) BN 6
J 0
(-3312 2108);
DISPLAY 0.489362 (-3312 2108);
PAINT GREEN (-3312 2108);
FORCEPROP 2 LAST CDS_LIB mstr_standard
J 2
(-3250 2100);
DISPLAY 0.723404 (-3250 2100);
PAINT MONO (-3250 2100);
DISPLAY INVISIBLE (-3250 2100);
FORCEPROP 1 LAST BODY_TYPE PLUMBING
J 0
(-3250 2150);
DISPLAY 0.872340 (-3250 2150);
PAINT GREEN (-3250 2150);
DISPLAY INVISIBLE (-3250 2150);
FORCEPROP 1 LAST HDL_TAP TRUE
J 0
(-2925 1975);
DISPLAY 0.872340 (-2925 1975);
DISPLAY INVISIBLE (-2925 1975);
FORCEPROP 1 LAST PATH I232
J 0
(-3252 2100);
DISPLAY 0.872340 (-3252 2100);
PAINT GREEN (-3252 2100);
DISPLAY INVISIBLE (-3252 2100);
FORCEADD TAP..1
(-3250 2150);
FORCEPROP 3 LASTPIN (-3300 2150) SIG_NAME M_J_CPU0_SA_CB<5>
J 0
(-3290 2160);
DISPLAY 0.659574 (-3290 2160);
PAINT MONO (-3290 2160);
DISPLAY INVISIBLE (-3290 2160);
FORCEPROP 1 LASTPIN (-3300 2150) BN 5
J 0
(-3312 2158);
DISPLAY 0.489362 (-3312 2158);
PAINT GREEN (-3312 2158);
FORCEPROP 2 LAST CDS_LIB mstr_standard
J 2
(-3250 2150);
DISPLAY 0.723404 (-3250 2150);
PAINT MONO (-3250 2150);
DISPLAY INVISIBLE (-3250 2150);
FORCEPROP 1 LAST BODY_TYPE PLUMBING
J 0
(-3250 2200);
DISPLAY 0.872340 (-3250 2200);
PAINT GREEN (-3250 2200);
DISPLAY INVISIBLE (-3250 2200);
FORCEPROP 1 LAST HDL_TAP TRUE
J 0
(-2925 2025);
DISPLAY 0.872340 (-2925 2025);
DISPLAY INVISIBLE (-2925 2025);
FORCEPROP 1 LAST PATH I233
J 0
(-3252 2150);
DISPLAY 0.872340 (-3252 2150);
PAINT GREEN (-3252 2150);
DISPLAY INVISIBLE (-3252 2150);
FORCEADD TAP..1
(-3250 2050);
FORCEPROP 3 LASTPIN (-3300 2050) SIG_NAME M_J_CPU0_SA_CB<7>
J 0
(-3290 2060);
DISPLAY 0.659574 (-3290 2060);
PAINT MONO (-3290 2060);
DISPLAY INVISIBLE (-3290 2060);
FORCEPROP 1 LASTPIN (-3300 2050) BN 7
J 0
(-3312 2058);
DISPLAY 0.489362 (-3312 2058);
PAINT GREEN (-3312 2058);
FORCEPROP 2 LAST CDS_LIB mstr_standard
J 2
(-3250 2050);
DISPLAY 0.723404 (-3250 2050);
PAINT MONO (-3250 2050);
DISPLAY INVISIBLE (-3250 2050);
FORCEPROP 1 LAST BODY_TYPE PLUMBING
J 0
(-3250 2100);
DISPLAY 0.872340 (-3250 2100);
PAINT GREEN (-3250 2100);
DISPLAY INVISIBLE (-3250 2100);
FORCEPROP 1 LAST HDL_TAP TRUE
J 0
(-2925 1925);
DISPLAY 0.872340 (-2925 1925);
DISPLAY INVISIBLE (-2925 1925);
FORCEPROP 1 LAST PATH I234
J 0
(-3252 2050);
DISPLAY 0.872340 (-3252 2050);
PAINT GREEN (-3252 2050);
DISPLAY INVISIBLE (-3252 2050);
FORCEADD OFFPAGE..6
R 2
(-2650 2000);
FORCEPROP 2 LAST $XR0 94 
J 0
(-2436 2000);
DISPLAY 0.638298 (-2436 2000);
PAINT MONO (-2436 2000);
FORCEPROP 2 LAST PATH I235
J 0
(-2425 2050);
DISPLAY 1.021277 (-2425 2050);
DISPLAY INVISIBLE (-2425 2050);
FORCEPROP 1 LAST COMMENT_BODY TRUE
J 2
(-2750 1925);
DISPLAY 0.872340 (-2750 1925);
PAINT GREEN (-2750 1925);
DISPLAY INVISIBLE (-2750 1925);
FORCEPROP 1 LAST OFFPAGE TRUE
J 2
(-2975 1875);
DISPLAY 0.872340 (-2975 1875);
PAINT GREEN (-2975 1875);
DISPLAY INVISIBLE (-2975 1875);
FORCEPROP 2 LAST CDS_LIB mstr_standard
J 2
(-2650 2000);
DISPLAY 0.723404 (-2650 2000);
PAINT MONO (-2650 2000);
DISPLAY INVISIBLE (-2650 2000);
FORCEADD TAP..1
(-3250 1950);
FORCEPROP 3 LASTPIN (-3300 1950) SIG_NAME M_J_CPU0_SB_CB<0>
J 0
(-3290 1960);
DISPLAY 0.659574 (-3290 1960);
PAINT MONO (-3290 1960);
DISPLAY INVISIBLE (-3290 1960);
FORCEPROP 1 LASTPIN (-3300 1950) BN 0
J 0
(-3312 1958);
DISPLAY 0.489362 (-3312 1958);
PAINT GREEN (-3312 1958);
FORCEPROP 2 LAST CDS_LIB mstr_standard
J 2
(-3250 1950);
DISPLAY 0.723404 (-3250 1950);
PAINT MONO (-3250 1950);
DISPLAY INVISIBLE (-3250 1950);
FORCEPROP 1 LAST BODY_TYPE PLUMBING
J 0
(-3250 2000);
DISPLAY 0.872340 (-3250 2000);
PAINT GREEN (-3250 2000);
DISPLAY INVISIBLE (-3250 2000);
FORCEPROP 1 LAST HDL_TAP TRUE
J 0
(-2925 1825);
DISPLAY 0.872340 (-2925 1825);
DISPLAY INVISIBLE (-2925 1825);
FORCEPROP 1 LAST PATH I236
J 0
(-3252 1950);
DISPLAY 0.872340 (-3252 1950);
PAINT GREEN (-3252 1950);
DISPLAY INVISIBLE (-3252 1950);
FORCEADD TAP..1
(-3250 1800);
FORCEPROP 3 LASTPIN (-3300 1800) SIG_NAME M_J_CPU0_SB_CB<3>
J 0
(-3290 1810);
DISPLAY 0.659574 (-3290 1810);
PAINT MONO (-3290 1810);
DISPLAY INVISIBLE (-3290 1810);
FORCEPROP 1 LASTPIN (-3300 1800) BN 3
J 0
(-3312 1808);
DISPLAY 0.489362 (-3312 1808);
PAINT GREEN (-3312 1808);
FORCEPROP 2 LAST CDS_LIB mstr_standard
J 2
(-3250 1800);
DISPLAY 0.723404 (-3250 1800);
PAINT MONO (-3250 1800);
DISPLAY INVISIBLE (-3250 1800);
FORCEPROP 1 LAST BODY_TYPE PLUMBING
J 0
(-3250 1850);
DISPLAY 0.872340 (-3250 1850);
PAINT GREEN (-3250 1850);
DISPLAY INVISIBLE (-3250 1850);
FORCEPROP 1 LAST HDL_TAP TRUE
J 0
(-2925 1675);
DISPLAY 0.872340 (-2925 1675);
DISPLAY INVISIBLE (-2925 1675);
FORCEPROP 1 LAST PATH I237
J 0
(-3252 1800);
DISPLAY 0.872340 (-3252 1800);
PAINT GREEN (-3252 1800);
DISPLAY INVISIBLE (-3252 1800);
FORCEADD TAP..1
(-3250 1900);
FORCEPROP 3 LASTPIN (-3300 1900) SIG_NAME M_J_CPU0_SB_CB<1>
J 0
(-3290 1910);
DISPLAY 0.659574 (-3290 1910);
PAINT MONO (-3290 1910);
DISPLAY INVISIBLE (-3290 1910);
FORCEPROP 1 LASTPIN (-3300 1900) BN 1
J 0
(-3312 1908);
DISPLAY 0.489362 (-3312 1908);
PAINT GREEN (-3312 1908);
FORCEPROP 2 LAST CDS_LIB mstr_standard
J 2
(-3250 1900);
DISPLAY 0.723404 (-3250 1900);
PAINT MONO (-3250 1900);
DISPLAY INVISIBLE (-3250 1900);
FORCEPROP 1 LAST BODY_TYPE PLUMBING
J 0
(-3250 1950);
DISPLAY 0.872340 (-3250 1950);
PAINT GREEN (-3250 1950);
DISPLAY INVISIBLE (-3250 1950);
FORCEPROP 1 LAST HDL_TAP TRUE
J 0
(-2925 1775);
DISPLAY 0.872340 (-2925 1775);
DISPLAY INVISIBLE (-2925 1775);
FORCEPROP 1 LAST PATH I238
J 0
(-3252 1900);
DISPLAY 0.872340 (-3252 1900);
PAINT GREEN (-3252 1900);
DISPLAY INVISIBLE (-3252 1900);
FORCEADD TAP..1
(-3250 1850);
FORCEPROP 3 LASTPIN (-3300 1850) SIG_NAME M_J_CPU0_SB_CB<2>
J 0
(-3290 1860);
DISPLAY 0.659574 (-3290 1860);
PAINT MONO (-3290 1860);
DISPLAY INVISIBLE (-3290 1860);
FORCEPROP 1 LASTPIN (-3300 1850) BN 2
J 0
(-3312 1858);
DISPLAY 0.489362 (-3312 1858);
PAINT GREEN (-3312 1858);
FORCEPROP 2 LAST CDS_LIB mstr_standard
J 2
(-3250 1850);
DISPLAY 0.723404 (-3250 1850);
PAINT MONO (-3250 1850);
DISPLAY INVISIBLE (-3250 1850);
FORCEPROP 1 LAST BODY_TYPE PLUMBING
J 0
(-3250 1900);
DISPLAY 0.872340 (-3250 1900);
PAINT GREEN (-3250 1900);
DISPLAY INVISIBLE (-3250 1900);
FORCEPROP 1 LAST HDL_TAP TRUE
J 0
(-2925 1725);
DISPLAY 0.872340 (-2925 1725);
DISPLAY INVISIBLE (-2925 1725);
FORCEPROP 1 LAST PATH I239
J 0
(-3252 1850);
DISPLAY 0.872340 (-3252 1850);
PAINT GREEN (-3252 1850);
DISPLAY INVISIBLE (-3252 1850);
FORCEADD TAP..1
(-3250 1750);
FORCEPROP 3 LASTPIN (-3300 1750) SIG_NAME M_J_CPU0_SB_CB<4>
J 0
(-3290 1760);
DISPLAY 0.659574 (-3290 1760);
PAINT MONO (-3290 1760);
DISPLAY INVISIBLE (-3290 1760);
FORCEPROP 1 LASTPIN (-3300 1750) BN 4
J 0
(-3312 1758);
DISPLAY 0.489362 (-3312 1758);
PAINT GREEN (-3312 1758);
FORCEPROP 2 LAST CDS_LIB mstr_standard
J 2
(-3250 1750);
DISPLAY 0.723404 (-3250 1750);
PAINT MONO (-3250 1750);
DISPLAY INVISIBLE (-3250 1750);
FORCEPROP 1 LAST BODY_TYPE PLUMBING
J 0
(-3250 1800);
DISPLAY 0.872340 (-3250 1800);
PAINT GREEN (-3250 1800);
DISPLAY INVISIBLE (-3250 1800);
FORCEPROP 1 LAST HDL_TAP TRUE
J 0
(-2925 1625);
DISPLAY 0.872340 (-2925 1625);
DISPLAY INVISIBLE (-2925 1625);
FORCEPROP 1 LAST PATH I240
J 0
(-3252 1750);
DISPLAY 0.872340 (-3252 1750);
PAINT GREEN (-3252 1750);
DISPLAY INVISIBLE (-3252 1750);
FORCEADD TAP..1
(-3250 1700);
FORCEPROP 3 LASTPIN (-3300 1700) SIG_NAME M_J_CPU0_SB_CB<5>
J 0
(-3290 1710);
DISPLAY 0.659574 (-3290 1710);
PAINT MONO (-3290 1710);
DISPLAY INVISIBLE (-3290 1710);
FORCEPROP 1 LASTPIN (-3300 1700) BN 5
J 0
(-3312 1708);
DISPLAY 0.489362 (-3312 1708);
PAINT GREEN (-3312 1708);
FORCEPROP 2 LAST CDS_LIB mstr_standard
J 2
(-3250 1700);
DISPLAY 0.723404 (-3250 1700);
PAINT MONO (-3250 1700);
DISPLAY INVISIBLE (-3250 1700);
FORCEPROP 1 LAST BODY_TYPE PLUMBING
J 0
(-3250 1750);
DISPLAY 0.872340 (-3250 1750);
PAINT GREEN (-3250 1750);
DISPLAY INVISIBLE (-3250 1750);
FORCEPROP 1 LAST HDL_TAP TRUE
J 0
(-2925 1575);
DISPLAY 0.872340 (-2925 1575);
DISPLAY INVISIBLE (-2925 1575);
FORCEPROP 1 LAST PATH I241
J 0
(-3252 1700);
DISPLAY 0.872340 (-3252 1700);
PAINT GREEN (-3252 1700);
DISPLAY INVISIBLE (-3252 1700);
FORCEADD TAP..1
(-3250 1650);
FORCEPROP 3 LASTPIN (-3300 1650) SIG_NAME M_J_CPU0_SB_CB<6>
J 0
(-3290 1660);
DISPLAY 0.659574 (-3290 1660);
PAINT MONO (-3290 1660);
DISPLAY INVISIBLE (-3290 1660);
FORCEPROP 1 LASTPIN (-3300 1650) BN 6
J 0
(-3312 1658);
DISPLAY 0.489362 (-3312 1658);
PAINT GREEN (-3312 1658);
FORCEPROP 2 LAST CDS_LIB mstr_standard
J 2
(-3250 1650);
DISPLAY 0.723404 (-3250 1650);
PAINT MONO (-3250 1650);
DISPLAY INVISIBLE (-3250 1650);
FORCEPROP 1 LAST BODY_TYPE PLUMBING
J 0
(-3250 1700);
DISPLAY 0.872340 (-3250 1700);
PAINT GREEN (-3250 1700);
DISPLAY INVISIBLE (-3250 1700);
FORCEPROP 1 LAST HDL_TAP TRUE
J 0
(-2925 1525);
DISPLAY 0.872340 (-2925 1525);
DISPLAY INVISIBLE (-2925 1525);
FORCEPROP 1 LAST PATH I242
J 0
(-3252 1650);
DISPLAY 0.872340 (-3252 1650);
PAINT GREEN (-3252 1650);
DISPLAY INVISIBLE (-3252 1650);
FORCEADD TAP..1
(-3250 1600);
FORCEPROP 3 LASTPIN (-3300 1600) SIG_NAME M_J_CPU0_SB_CB<7>
J 0
(-3290 1610);
DISPLAY 0.659574 (-3290 1610);
PAINT MONO (-3290 1610);
DISPLAY INVISIBLE (-3290 1610);
FORCEPROP 1 LASTPIN (-3300 1600) BN 7
J 0
(-3312 1608);
DISPLAY 0.489362 (-3312 1608);
PAINT GREEN (-3312 1608);
FORCEPROP 2 LAST CDS_LIB mstr_standard
J 2
(-3250 1600);
DISPLAY 0.723404 (-3250 1600);
PAINT MONO (-3250 1600);
DISPLAY INVISIBLE (-3250 1600);
FORCEPROP 1 LAST BODY_TYPE PLUMBING
J 0
(-3250 1650);
DISPLAY 0.872340 (-3250 1650);
PAINT GREEN (-3250 1650);
DISPLAY INVISIBLE (-3250 1650);
FORCEPROP 1 LAST HDL_TAP TRUE
J 0
(-2925 1475);
DISPLAY 0.872340 (-2925 1475);
DISPLAY INVISIBLE (-2925 1475);
FORCEPROP 1 LAST PATH I243
J 0
(-3252 1600);
DISPLAY 0.872340 (-3252 1600);
PAINT GREEN (-3252 1600);
DISPLAY INVISIBLE (-3252 1600);
FORCEADD TAP..1
R 2
(-5675 5900);
FORCEPROP 3 LASTPIN (-5625 5900) SIG_NAME M_J_CPU0_SA_DQS_DP<1>
J 0
(-5615 5910);
DISPLAY 0.659574 (-5615 5910);
PAINT MONO (-5615 5910);
DISPLAY INVISIBLE (-5615 5910);
FORCEPROP 1 LASTPIN (-5625 5900) BN 1
J 2
(-5613 5908);
DISPLAY 0.489362 (-5613 5908);
PAINT GREEN (-5613 5908);
FORCEPROP 2 LAST CDS_LIB mstr_standard
J 2
(-5675 5900);
DISPLAY 0.723404 (-5675 5900);
PAINT MONO (-5675 5900);
DISPLAY INVISIBLE (-5675 5900);
FORCEPROP 1 LAST BODY_TYPE PLUMBING
J 2
(-5675 5950);
DISPLAY 0.872340 (-5675 5950);
PAINT GREEN (-5675 5950);
DISPLAY INVISIBLE (-5675 5950);
FORCEPROP 1 LAST HDL_TAP TRUE
J 2
(-6000 5775);
DISPLAY 0.872340 (-6000 5775);
DISPLAY INVISIBLE (-6000 5775);
FORCEPROP 1 LAST PATH I244
J 2
(-5673 5900);
DISPLAY 0.872340 (-5673 5900);
PAINT GREEN (-5673 5900);
DISPLAY INVISIBLE (-5673 5900);
FORCEADD TAP..1
R 2
(-5675 6000);
FORCEPROP 3 LASTPIN (-5625 6000) SIG_NAME M_J_CPU0_SA_DQS_DP<0>
J 0
(-5615 6010);
DISPLAY 0.659574 (-5615 6010);
PAINT MONO (-5615 6010);
DISPLAY INVISIBLE (-5615 6010);
FORCEPROP 1 LASTPIN (-5625 6000) BN 0
J 2
(-5613 6008);
DISPLAY 0.489362 (-5613 6008);
PAINT GREEN (-5613 6008);
FORCEPROP 2 LAST CDS_LIB mstr_standard
J 2
(-5675 6000);
DISPLAY 0.723404 (-5675 6000);
PAINT MONO (-5675 6000);
DISPLAY INVISIBLE (-5675 6000);
FORCEPROP 1 LAST BODY_TYPE PLUMBING
J 2
(-5675 6050);
DISPLAY 0.872340 (-5675 6050);
PAINT GREEN (-5675 6050);
DISPLAY INVISIBLE (-5675 6050);
FORCEPROP 1 LAST HDL_TAP TRUE
J 2
(-6000 5875);
DISPLAY 0.872340 (-6000 5875);
DISPLAY INVISIBLE (-6000 5875);
FORCEPROP 1 LAST PATH I245
J 2
(-5673 6000);
DISPLAY 0.872340 (-5673 6000);
PAINT GREEN (-5673 6000);
DISPLAY INVISIBLE (-5673 6000);
FORCEADD TAP..1
R 2
(-5675 5800);
FORCEPROP 3 LASTPIN (-5625 5800) SIG_NAME M_J_CPU0_SA_DQS_DP<2>
J 0
(-5615 5810);
DISPLAY 0.659574 (-5615 5810);
PAINT MONO (-5615 5810);
DISPLAY INVISIBLE (-5615 5810);
FORCEPROP 1 LASTPIN (-5625 5800) BN 2
J 2
(-5613 5808);
DISPLAY 0.489362 (-5613 5808);
PAINT GREEN (-5613 5808);
FORCEPROP 2 LAST CDS_LIB mstr_standard
J 2
(-5675 5800);
DISPLAY 0.723404 (-5675 5800);
PAINT MONO (-5675 5800);
DISPLAY INVISIBLE (-5675 5800);
FORCEPROP 1 LAST BODY_TYPE PLUMBING
J 2
(-5675 5850);
DISPLAY 0.872340 (-5675 5850);
PAINT GREEN (-5675 5850);
DISPLAY INVISIBLE (-5675 5850);
FORCEPROP 1 LAST HDL_TAP TRUE
J 2
(-6000 5675);
DISPLAY 0.872340 (-6000 5675);
DISPLAY INVISIBLE (-6000 5675);
FORCEPROP 1 LAST PATH I246
J 2
(-5673 5800);
DISPLAY 0.872340 (-5673 5800);
PAINT GREEN (-5673 5800);
DISPLAY INVISIBLE (-5673 5800);
FORCEADD TAP..1
R 2
(-5675 5700);
FORCEPROP 3 LASTPIN (-5625 5700) SIG_NAME M_J_CPU0_SA_DQS_DP<3>
J 0
(-5615 5710);
DISPLAY 0.659574 (-5615 5710);
PAINT MONO (-5615 5710);
DISPLAY INVISIBLE (-5615 5710);
FORCEPROP 1 LASTPIN (-5625 5700) BN 3
J 2
(-5613 5708);
DISPLAY 0.489362 (-5613 5708);
PAINT GREEN (-5613 5708);
FORCEPROP 2 LAST CDS_LIB mstr_standard
J 2
(-5675 5700);
DISPLAY 0.723404 (-5675 5700);
PAINT MONO (-5675 5700);
DISPLAY INVISIBLE (-5675 5700);
FORCEPROP 1 LAST BODY_TYPE PLUMBING
J 2
(-5675 5750);
DISPLAY 0.872340 (-5675 5750);
PAINT GREEN (-5675 5750);
DISPLAY INVISIBLE (-5675 5750);
FORCEPROP 1 LAST HDL_TAP TRUE
J 2
(-6000 5575);
DISPLAY 0.872340 (-6000 5575);
DISPLAY INVISIBLE (-6000 5575);
FORCEPROP 1 LAST PATH I247
J 2
(-5673 5700);
DISPLAY 0.872340 (-5673 5700);
PAINT GREEN (-5673 5700);
DISPLAY INVISIBLE (-5673 5700);
FORCEADD TAP..1
R 2
(-5875 5950);
FORCEPROP 3 LASTPIN (-5825 5950) SIG_NAME M_J_CPU0_SA_DQS_DN<0>
J 0
(-5815 5960);
DISPLAY 0.659574 (-5815 5960);
PAINT MONO (-5815 5960);
DISPLAY INVISIBLE (-5815 5960);
FORCEPROP 1 LASTPIN (-5825 5950) BN 0
J 2
(-5813 5958);
DISPLAY 0.489362 (-5813 5958);
PAINT GREEN (-5813 5958);
FORCEPROP 2 LAST CDS_LIB mstr_standard
J 2
(-5875 5950);
DISPLAY 0.723404 (-5875 5950);
PAINT MONO (-5875 5950);
DISPLAY INVISIBLE (-5875 5950);
FORCEPROP 1 LAST BODY_TYPE PLUMBING
J 2
(-5875 6000);
DISPLAY 0.872340 (-5875 6000);
PAINT GREEN (-5875 6000);
DISPLAY INVISIBLE (-5875 6000);
FORCEPROP 1 LAST HDL_TAP TRUE
J 2
(-6200 5825);
DISPLAY 0.872340 (-6200 5825);
DISPLAY INVISIBLE (-6200 5825);
FORCEPROP 1 LAST PATH I248
J 2
(-5873 5950);
DISPLAY 0.872340 (-5873 5950);
PAINT GREEN (-5873 5950);
DISPLAY INVISIBLE (-5873 5950);
FORCEADD TAP..1
R 2
(-5875 5650);
FORCEPROP 3 LASTPIN (-5825 5650) SIG_NAME M_J_CPU0_SA_DQS_DN<3>
J 0
(-5815 5660);
DISPLAY 0.659574 (-5815 5660);
PAINT MONO (-5815 5660);
DISPLAY INVISIBLE (-5815 5660);
FORCEPROP 1 LASTPIN (-5825 5650) BN 3
J 2
(-5813 5658);
DISPLAY 0.489362 (-5813 5658);
PAINT GREEN (-5813 5658);
FORCEPROP 2 LAST CDS_LIB mstr_standard
J 2
(-5875 5650);
DISPLAY 0.723404 (-5875 5650);
PAINT MONO (-5875 5650);
DISPLAY INVISIBLE (-5875 5650);
FORCEPROP 1 LAST BODY_TYPE PLUMBING
J 2
(-5875 5700);
DISPLAY 0.872340 (-5875 5700);
PAINT GREEN (-5875 5700);
DISPLAY INVISIBLE (-5875 5700);
FORCEPROP 1 LAST HDL_TAP TRUE
J 2
(-6200 5525);
DISPLAY 0.872340 (-6200 5525);
DISPLAY INVISIBLE (-6200 5525);
FORCEPROP 1 LAST PATH I249
J 2
(-5873 5650);
DISPLAY 0.872340 (-5873 5650);
PAINT GREEN (-5873 5650);
DISPLAY INVISIBLE (-5873 5650);
FORCEADD TAP..1
R 2
(-5875 5750);
FORCEPROP 3 LASTPIN (-5825 5750) SIG_NAME M_J_CPU0_SA_DQS_DN<2>
J 0
(-5815 5760);
DISPLAY 0.659574 (-5815 5760);
PAINT MONO (-5815 5760);
DISPLAY INVISIBLE (-5815 5760);
FORCEPROP 1 LASTPIN (-5825 5750) BN 2
J 2
(-5813 5758);
DISPLAY 0.489362 (-5813 5758);
PAINT GREEN (-5813 5758);
FORCEPROP 2 LAST CDS_LIB mstr_standard
J 2
(-5875 5750);
DISPLAY 0.723404 (-5875 5750);
PAINT MONO (-5875 5750);
DISPLAY INVISIBLE (-5875 5750);
FORCEPROP 1 LAST BODY_TYPE PLUMBING
J 2
(-5875 5800);
DISPLAY 0.872340 (-5875 5800);
PAINT GREEN (-5875 5800);
DISPLAY INVISIBLE (-5875 5800);
FORCEPROP 1 LAST HDL_TAP TRUE
J 2
(-6200 5625);
DISPLAY 0.872340 (-6200 5625);
DISPLAY INVISIBLE (-6200 5625);
FORCEPROP 1 LAST PATH I250
J 2
(-5873 5750);
DISPLAY 0.872340 (-5873 5750);
PAINT GREEN (-5873 5750);
DISPLAY INVISIBLE (-5873 5750);
FORCEADD TAP..1
R 2
(-5875 5850);
FORCEPROP 3 LASTPIN (-5825 5850) SIG_NAME M_J_CPU0_SA_DQS_DN<1>
J 0
(-5815 5860);
DISPLAY 0.659574 (-5815 5860);
PAINT MONO (-5815 5860);
DISPLAY INVISIBLE (-5815 5860);
FORCEPROP 1 LASTPIN (-5825 5850) BN 1
J 2
(-5813 5858);
DISPLAY 0.489362 (-5813 5858);
PAINT GREEN (-5813 5858);
FORCEPROP 2 LAST CDS_LIB mstr_standard
J 2
(-5875 5850);
DISPLAY 0.723404 (-5875 5850);
PAINT MONO (-5875 5850);
DISPLAY INVISIBLE (-5875 5850);
FORCEPROP 1 LAST BODY_TYPE PLUMBING
J 2
(-5875 5900);
DISPLAY 0.872340 (-5875 5900);
PAINT GREEN (-5875 5900);
DISPLAY INVISIBLE (-5875 5900);
FORCEPROP 1 LAST HDL_TAP TRUE
J 2
(-6200 5725);
DISPLAY 0.872340 (-6200 5725);
DISPLAY INVISIBLE (-6200 5725);
FORCEPROP 1 LAST PATH I251
J 2
(-5873 5850);
DISPLAY 0.872340 (-5873 5850);
PAINT GREEN (-5873 5850);
DISPLAY INVISIBLE (-5873 5850);
FORCEADD TAP..1
R 2
(-5675 5600);
FORCEPROP 3 LASTPIN (-5625 5600) SIG_NAME M_J_CPU0_SA_DQS_DP<4>
J 0
(-5615 5610);
DISPLAY 0.659574 (-5615 5610);
PAINT MONO (-5615 5610);
DISPLAY INVISIBLE (-5615 5610);
FORCEPROP 1 LASTPIN (-5625 5600) BN 4
J 2
(-5613 5608);
DISPLAY 0.489362 (-5613 5608);
PAINT GREEN (-5613 5608);
FORCEPROP 2 LAST CDS_LIB mstr_standard
J 2
(-5675 5600);
DISPLAY 0.723404 (-5675 5600);
PAINT MONO (-5675 5600);
DISPLAY INVISIBLE (-5675 5600);
FORCEPROP 1 LAST BODY_TYPE PLUMBING
J 2
(-5675 5650);
DISPLAY 0.872340 (-5675 5650);
PAINT GREEN (-5675 5650);
DISPLAY INVISIBLE (-5675 5650);
FORCEPROP 1 LAST HDL_TAP TRUE
J 2
(-6000 5475);
DISPLAY 0.872340 (-6000 5475);
DISPLAY INVISIBLE (-6000 5475);
FORCEPROP 1 LAST PATH I252
J 2
(-5673 5600);
DISPLAY 0.872340 (-5673 5600);
PAINT GREEN (-5673 5600);
DISPLAY INVISIBLE (-5673 5600);
FORCEADD TAP..1
R 2
(-5675 5500);
FORCEPROP 3 LASTPIN (-5625 5500) SIG_NAME M_J_CPU0_SA_DQS_DP<5>
J 0
(-5615 5510);
DISPLAY 0.659574 (-5615 5510);
PAINT MONO (-5615 5510);
DISPLAY INVISIBLE (-5615 5510);
FORCEPROP 1 LASTPIN (-5625 5500) BN 5
J 2
(-5613 5508);
DISPLAY 0.489362 (-5613 5508);
PAINT GREEN (-5613 5508);
FORCEPROP 2 LAST CDS_LIB mstr_standard
J 2
(-5675 5500);
DISPLAY 0.723404 (-5675 5500);
PAINT MONO (-5675 5500);
DISPLAY INVISIBLE (-5675 5500);
FORCEPROP 1 LAST BODY_TYPE PLUMBING
J 2
(-5675 5550);
DISPLAY 0.872340 (-5675 5550);
PAINT GREEN (-5675 5550);
DISPLAY INVISIBLE (-5675 5550);
FORCEPROP 1 LAST HDL_TAP TRUE
J 2
(-6000 5375);
DISPLAY 0.872340 (-6000 5375);
DISPLAY INVISIBLE (-6000 5375);
FORCEPROP 1 LAST PATH I253
J 2
(-5673 5500);
DISPLAY 0.872340 (-5673 5500);
PAINT GREEN (-5673 5500);
DISPLAY INVISIBLE (-5673 5500);
FORCEADD TAP..1
R 2
(-5675 5400);
FORCEPROP 3 LASTPIN (-5625 5400) SIG_NAME M_J_CPU0_SA_DQS_DP<6>
J 0
(-5615 5410);
DISPLAY 0.659574 (-5615 5410);
PAINT MONO (-5615 5410);
DISPLAY INVISIBLE (-5615 5410);
FORCEPROP 1 LASTPIN (-5625 5400) BN 6
J 2
(-5613 5408);
DISPLAY 0.489362 (-5613 5408);
PAINT GREEN (-5613 5408);
FORCEPROP 2 LAST CDS_LIB mstr_standard
J 2
(-5675 5400);
DISPLAY 0.723404 (-5675 5400);
PAINT MONO (-5675 5400);
DISPLAY INVISIBLE (-5675 5400);
FORCEPROP 1 LAST BODY_TYPE PLUMBING
J 2
(-5675 5450);
DISPLAY 0.872340 (-5675 5450);
PAINT GREEN (-5675 5450);
DISPLAY INVISIBLE (-5675 5450);
FORCEPROP 1 LAST HDL_TAP TRUE
J 2
(-6000 5275);
DISPLAY 0.872340 (-6000 5275);
DISPLAY INVISIBLE (-6000 5275);
FORCEPROP 1 LAST PATH I254
J 2
(-5673 5400);
DISPLAY 0.872340 (-5673 5400);
PAINT GREEN (-5673 5400);
DISPLAY INVISIBLE (-5673 5400);
FORCEADD TAP..1
R 2
(-5675 5300);
FORCEPROP 3 LASTPIN (-5625 5300) SIG_NAME M_J_CPU0_SA_DQS_DP<7>
J 0
(-5615 5310);
DISPLAY 0.659574 (-5615 5310);
PAINT MONO (-5615 5310);
DISPLAY INVISIBLE (-5615 5310);
FORCEPROP 1 LASTPIN (-5625 5300) BN 7
J 2
(-5613 5308);
DISPLAY 0.489362 (-5613 5308);
PAINT GREEN (-5613 5308);
FORCEPROP 2 LAST CDS_LIB mstr_standard
J 2
(-5675 5300);
DISPLAY 0.723404 (-5675 5300);
PAINT MONO (-5675 5300);
DISPLAY INVISIBLE (-5675 5300);
FORCEPROP 1 LAST BODY_TYPE PLUMBING
J 2
(-5675 5350);
DISPLAY 0.872340 (-5675 5350);
PAINT GREEN (-5675 5350);
DISPLAY INVISIBLE (-5675 5350);
FORCEPROP 1 LAST HDL_TAP TRUE
J 2
(-6000 5175);
DISPLAY 0.872340 (-6000 5175);
DISPLAY INVISIBLE (-6000 5175);
FORCEPROP 1 LAST PATH I255
J 2
(-5673 5300);
DISPLAY 0.872340 (-5673 5300);
PAINT GREEN (-5673 5300);
DISPLAY INVISIBLE (-5673 5300);
FORCEADD TAP..1
R 2
(-5675 5200);
FORCEPROP 3 LASTPIN (-5625 5200) SIG_NAME M_J_CPU0_SA_DQS_DP<8>
J 0
(-5615 5210);
DISPLAY 0.659574 (-5615 5210);
PAINT MONO (-5615 5210);
DISPLAY INVISIBLE (-5615 5210);
FORCEPROP 1 LASTPIN (-5625 5200) BN 8
J 2
(-5613 5208);
DISPLAY 0.489362 (-5613 5208);
PAINT GREEN (-5613 5208);
FORCEPROP 2 LAST CDS_LIB mstr_standard
J 2
(-5675 5200);
DISPLAY 0.723404 (-5675 5200);
PAINT MONO (-5675 5200);
DISPLAY INVISIBLE (-5675 5200);
FORCEPROP 1 LAST BODY_TYPE PLUMBING
J 2
(-5675 5250);
DISPLAY 0.872340 (-5675 5250);
PAINT GREEN (-5675 5250);
DISPLAY INVISIBLE (-5675 5250);
FORCEPROP 1 LAST HDL_TAP TRUE
J 2
(-6000 5075);
DISPLAY 0.872340 (-6000 5075);
DISPLAY INVISIBLE (-6000 5075);
FORCEPROP 1 LAST PATH I256
J 2
(-5673 5200);
DISPLAY 0.872340 (-5673 5200);
PAINT GREEN (-5673 5200);
DISPLAY INVISIBLE (-5673 5200);
FORCEADD TAP..1
R 2
(-5875 5450);
FORCEPROP 3 LASTPIN (-5825 5450) SIG_NAME M_J_CPU0_SA_DQS_DN<5>
J 0
(-5815 5460);
DISPLAY 0.659574 (-5815 5460);
PAINT MONO (-5815 5460);
DISPLAY INVISIBLE (-5815 5460);
FORCEPROP 1 LASTPIN (-5825 5450) BN 5
J 2
(-5813 5458);
DISPLAY 0.489362 (-5813 5458);
PAINT GREEN (-5813 5458);
FORCEPROP 2 LAST CDS_LIB mstr_standard
J 2
(-5875 5450);
DISPLAY 0.723404 (-5875 5450);
PAINT MONO (-5875 5450);
DISPLAY INVISIBLE (-5875 5450);
FORCEPROP 1 LAST BODY_TYPE PLUMBING
J 2
(-5875 5500);
DISPLAY 0.872340 (-5875 5500);
PAINT GREEN (-5875 5500);
DISPLAY INVISIBLE (-5875 5500);
FORCEPROP 1 LAST HDL_TAP TRUE
J 2
(-6200 5325);
DISPLAY 0.872340 (-6200 5325);
DISPLAY INVISIBLE (-6200 5325);
FORCEPROP 1 LAST PATH I257
J 2
(-5873 5450);
DISPLAY 0.872340 (-5873 5450);
PAINT GREEN (-5873 5450);
DISPLAY INVISIBLE (-5873 5450);
FORCEADD TAP..1
R 2
(-5875 5550);
FORCEPROP 3 LASTPIN (-5825 5550) SIG_NAME M_J_CPU0_SA_DQS_DN<4>
J 0
(-5815 5560);
DISPLAY 0.659574 (-5815 5560);
PAINT MONO (-5815 5560);
DISPLAY INVISIBLE (-5815 5560);
FORCEPROP 1 LASTPIN (-5825 5550) BN 4
J 2
(-5813 5558);
DISPLAY 0.489362 (-5813 5558);
PAINT GREEN (-5813 5558);
FORCEPROP 2 LAST CDS_LIB mstr_standard
J 2
(-5875 5550);
DISPLAY 0.723404 (-5875 5550);
PAINT MONO (-5875 5550);
DISPLAY INVISIBLE (-5875 5550);
FORCEPROP 1 LAST BODY_TYPE PLUMBING
J 2
(-5875 5600);
DISPLAY 0.872340 (-5875 5600);
PAINT GREEN (-5875 5600);
DISPLAY INVISIBLE (-5875 5600);
FORCEPROP 1 LAST HDL_TAP TRUE
J 2
(-6200 5425);
DISPLAY 0.872340 (-6200 5425);
DISPLAY INVISIBLE (-6200 5425);
FORCEPROP 1 LAST PATH I258
J 2
(-5873 5550);
DISPLAY 0.872340 (-5873 5550);
PAINT GREEN (-5873 5550);
DISPLAY INVISIBLE (-5873 5550);
FORCEADD TAP..1
R 2
(-5875 5150);
FORCEPROP 3 LASTPIN (-5825 5150) SIG_NAME M_J_CPU0_SA_DQS_DN<8>
J 0
(-5815 5160);
DISPLAY 0.659574 (-5815 5160);
PAINT MONO (-5815 5160);
DISPLAY INVISIBLE (-5815 5160);
FORCEPROP 1 LASTPIN (-5825 5150) BN 8
J 2
(-5813 5158);
DISPLAY 0.489362 (-5813 5158);
PAINT GREEN (-5813 5158);
FORCEPROP 2 LAST CDS_LIB mstr_standard
J 2
(-5875 5150);
DISPLAY 0.723404 (-5875 5150);
PAINT MONO (-5875 5150);
DISPLAY INVISIBLE (-5875 5150);
FORCEPROP 1 LAST BODY_TYPE PLUMBING
J 2
(-5875 5200);
DISPLAY 0.872340 (-5875 5200);
PAINT GREEN (-5875 5200);
DISPLAY INVISIBLE (-5875 5200);
FORCEPROP 1 LAST HDL_TAP TRUE
J 2
(-6200 5025);
DISPLAY 0.872340 (-6200 5025);
DISPLAY INVISIBLE (-6200 5025);
FORCEPROP 1 LAST PATH I259
J 2
(-5873 5150);
DISPLAY 0.872340 (-5873 5150);
PAINT GREEN (-5873 5150);
DISPLAY INVISIBLE (-5873 5150);
FORCEADD TAP..1
R 2
(-5875 5350);
FORCEPROP 3 LASTPIN (-5825 5350) SIG_NAME M_J_CPU0_SA_DQS_DN<6>
J 0
(-5815 5360);
DISPLAY 0.659574 (-5815 5360);
PAINT MONO (-5815 5360);
DISPLAY INVISIBLE (-5815 5360);
FORCEPROP 1 LASTPIN (-5825 5350) BN 6
J 2
(-5813 5358);
DISPLAY 0.489362 (-5813 5358);
PAINT GREEN (-5813 5358);
FORCEPROP 2 LAST CDS_LIB mstr_standard
J 2
(-5875 5350);
DISPLAY 0.723404 (-5875 5350);
PAINT MONO (-5875 5350);
DISPLAY INVISIBLE (-5875 5350);
FORCEPROP 1 LAST BODY_TYPE PLUMBING
J 2
(-5875 5400);
DISPLAY 0.872340 (-5875 5400);
PAINT GREEN (-5875 5400);
DISPLAY INVISIBLE (-5875 5400);
FORCEPROP 1 LAST HDL_TAP TRUE
J 2
(-6200 5225);
DISPLAY 0.872340 (-6200 5225);
DISPLAY INVISIBLE (-6200 5225);
FORCEPROP 1 LAST PATH I260
J 2
(-5873 5350);
DISPLAY 0.872340 (-5873 5350);
PAINT GREEN (-5873 5350);
DISPLAY INVISIBLE (-5873 5350);
FORCEADD TAP..1
R 2
(-5875 5250);
FORCEPROP 3 LASTPIN (-5825 5250) SIG_NAME M_J_CPU0_SA_DQS_DN<7>
J 0
(-5815 5260);
DISPLAY 0.659574 (-5815 5260);
PAINT MONO (-5815 5260);
DISPLAY INVISIBLE (-5815 5260);
FORCEPROP 1 LASTPIN (-5825 5250) BN 7
J 2
(-5813 5258);
DISPLAY 0.489362 (-5813 5258);
PAINT GREEN (-5813 5258);
FORCEPROP 2 LAST CDS_LIB mstr_standard
J 2
(-5875 5250);
DISPLAY 0.723404 (-5875 5250);
PAINT MONO (-5875 5250);
DISPLAY INVISIBLE (-5875 5250);
FORCEPROP 1 LAST BODY_TYPE PLUMBING
J 2
(-5875 5300);
DISPLAY 0.872340 (-5875 5300);
PAINT GREEN (-5875 5300);
DISPLAY INVISIBLE (-5875 5300);
FORCEPROP 1 LAST HDL_TAP TRUE
J 2
(-6200 5125);
DISPLAY 0.872340 (-6200 5125);
DISPLAY INVISIBLE (-6200 5125);
FORCEPROP 1 LAST PATH I261
J 2
(-5873 5250);
DISPLAY 0.872340 (-5873 5250);
PAINT GREEN (-5873 5250);
DISPLAY INVISIBLE (-5873 5250);
FORCEADD TAP..1
R 2
(-5675 4950);
FORCEPROP 3 LASTPIN (-5625 4950) SIG_NAME M_J_CPU0_SB_DQS_DP<0>
J 0
(-5615 4960);
DISPLAY 0.659574 (-5615 4960);
PAINT MONO (-5615 4960);
DISPLAY INVISIBLE (-5615 4960);
FORCEPROP 1 LASTPIN (-5625 4950) BN 0
J 2
(-5613 4958);
DISPLAY 0.489362 (-5613 4958);
PAINT GREEN (-5613 4958);
FORCEPROP 2 LAST CDS_LIB mstr_standard
J 2
(-5675 4950);
DISPLAY 0.723404 (-5675 4950);
PAINT MONO (-5675 4950);
DISPLAY INVISIBLE (-5675 4950);
FORCEPROP 1 LAST BODY_TYPE PLUMBING
J 2
(-5675 5000);
DISPLAY 0.872340 (-5675 5000);
PAINT GREEN (-5675 5000);
DISPLAY INVISIBLE (-5675 5000);
FORCEPROP 1 LAST HDL_TAP TRUE
J 2
(-6000 4825);
DISPLAY 0.872340 (-6000 4825);
DISPLAY INVISIBLE (-6000 4825);
FORCEPROP 1 LAST PATH I262
J 2
(-5673 4950);
DISPLAY 0.872340 (-5673 4950);
PAINT GREEN (-5673 4950);
DISPLAY INVISIBLE (-5673 4950);
FORCEADD TAP..1
R 2
(-5675 5100);
FORCEPROP 3 LASTPIN (-5625 5100) SIG_NAME M_J_CPU0_SA_DQS_DP<9>
J 0
(-5615 5110);
DISPLAY 0.659574 (-5615 5110);
PAINT MONO (-5615 5110);
DISPLAY INVISIBLE (-5615 5110);
FORCEPROP 1 LASTPIN (-5625 5100) BN 9
J 2
(-5613 5108);
DISPLAY 0.489362 (-5613 5108);
PAINT GREEN (-5613 5108);
FORCEPROP 2 LAST CDS_LIB mstr_standard
J 2
(-5675 5100);
DISPLAY 0.723404 (-5675 5100);
PAINT MONO (-5675 5100);
DISPLAY INVISIBLE (-5675 5100);
FORCEPROP 1 LAST BODY_TYPE PLUMBING
J 2
(-5675 5150);
DISPLAY 0.872340 (-5675 5150);
PAINT GREEN (-5675 5150);
DISPLAY INVISIBLE (-5675 5150);
FORCEPROP 1 LAST HDL_TAP TRUE
J 2
(-6000 4975);
DISPLAY 0.872340 (-6000 4975);
DISPLAY INVISIBLE (-6000 4975);
FORCEPROP 1 LAST PATH I263
J 2
(-5673 5100);
DISPLAY 0.872340 (-5673 5100);
PAINT GREEN (-5673 5100);
DISPLAY INVISIBLE (-5673 5100);
FORCEADD TAP..1
R 2
(-5675 4850);
FORCEPROP 3 LASTPIN (-5625 4850) SIG_NAME M_J_CPU0_SB_DQS_DP<1>
J 0
(-5615 4860);
DISPLAY 0.659574 (-5615 4860);
PAINT MONO (-5615 4860);
DISPLAY INVISIBLE (-5615 4860);
FORCEPROP 1 LASTPIN (-5625 4850) BN 1
J 2
(-5613 4858);
DISPLAY 0.489362 (-5613 4858);
PAINT GREEN (-5613 4858);
FORCEPROP 2 LAST CDS_LIB mstr_standard
J 2
(-5675 4850);
DISPLAY 0.723404 (-5675 4850);
PAINT MONO (-5675 4850);
DISPLAY INVISIBLE (-5675 4850);
FORCEPROP 1 LAST BODY_TYPE PLUMBING
J 2
(-5675 4900);
DISPLAY 0.872340 (-5675 4900);
PAINT GREEN (-5675 4900);
DISPLAY INVISIBLE (-5675 4900);
FORCEPROP 1 LAST HDL_TAP TRUE
J 2
(-6000 4725);
DISPLAY 0.872340 (-6000 4725);
DISPLAY INVISIBLE (-6000 4725);
FORCEPROP 1 LAST PATH I264
J 2
(-5673 4850);
DISPLAY 0.872340 (-5673 4850);
PAINT GREEN (-5673 4850);
DISPLAY INVISIBLE (-5673 4850);
FORCEADD TAP..1
R 2
(-5675 4750);
FORCEPROP 3 LASTPIN (-5625 4750) SIG_NAME M_J_CPU0_SB_DQS_DP<2>
J 0
(-5615 4760);
DISPLAY 0.659574 (-5615 4760);
PAINT MONO (-5615 4760);
DISPLAY INVISIBLE (-5615 4760);
FORCEPROP 1 LASTPIN (-5625 4750) BN 2
J 2
(-5613 4758);
DISPLAY 0.489362 (-5613 4758);
PAINT GREEN (-5613 4758);
FORCEPROP 2 LAST CDS_LIB mstr_standard
J 2
(-5675 4750);
DISPLAY 0.723404 (-5675 4750);
PAINT MONO (-5675 4750);
DISPLAY INVISIBLE (-5675 4750);
FORCEPROP 1 LAST BODY_TYPE PLUMBING
J 2
(-5675 4800);
DISPLAY 0.872340 (-5675 4800);
PAINT GREEN (-5675 4800);
DISPLAY INVISIBLE (-5675 4800);
FORCEPROP 1 LAST HDL_TAP TRUE
J 2
(-6000 4625);
DISPLAY 0.872340 (-6000 4625);
DISPLAY INVISIBLE (-6000 4625);
FORCEPROP 1 LAST PATH I265
J 2
(-5673 4750);
DISPLAY 0.872340 (-5673 4750);
PAINT GREEN (-5673 4750);
DISPLAY INVISIBLE (-5673 4750);
FORCEADD TAP..1
R 2
(-5675 4650);
FORCEPROP 3 LASTPIN (-5625 4650) SIG_NAME M_J_CPU0_SB_DQS_DP<3>
J 0
(-5615 4660);
DISPLAY 0.659574 (-5615 4660);
PAINT MONO (-5615 4660);
DISPLAY INVISIBLE (-5615 4660);
FORCEPROP 1 LASTPIN (-5625 4650) BN 3
J 2
(-5613 4658);
DISPLAY 0.489362 (-5613 4658);
PAINT GREEN (-5613 4658);
FORCEPROP 2 LAST CDS_LIB mstr_standard
J 2
(-5675 4650);
DISPLAY 0.723404 (-5675 4650);
PAINT MONO (-5675 4650);
DISPLAY INVISIBLE (-5675 4650);
FORCEPROP 1 LAST BODY_TYPE PLUMBING
J 2
(-5675 4700);
DISPLAY 0.872340 (-5675 4700);
PAINT GREEN (-5675 4700);
DISPLAY INVISIBLE (-5675 4700);
FORCEPROP 1 LAST HDL_TAP TRUE
J 2
(-6000 4525);
DISPLAY 0.872340 (-6000 4525);
DISPLAY INVISIBLE (-6000 4525);
FORCEPROP 1 LAST PATH I266
J 2
(-5673 4650);
DISPLAY 0.872340 (-5673 4650);
PAINT GREEN (-5673 4650);
DISPLAY INVISIBLE (-5673 4650);
FORCEADD TAP..1
R 2
(-5875 4900);
FORCEPROP 3 LASTPIN (-5825 4900) SIG_NAME M_J_CPU0_SB_DQS_DN<0>
J 0
(-5815 4910);
DISPLAY 0.659574 (-5815 4910);
PAINT MONO (-5815 4910);
DISPLAY INVISIBLE (-5815 4910);
FORCEPROP 1 LASTPIN (-5825 4900) BN 0
J 2
(-5813 4908);
DISPLAY 0.489362 (-5813 4908);
PAINT GREEN (-5813 4908);
FORCEPROP 2 LAST CDS_LIB mstr_standard
J 2
(-5875 4900);
DISPLAY 0.723404 (-5875 4900);
PAINT MONO (-5875 4900);
DISPLAY INVISIBLE (-5875 4900);
FORCEPROP 1 LAST BODY_TYPE PLUMBING
J 2
(-5875 4950);
DISPLAY 0.872340 (-5875 4950);
PAINT GREEN (-5875 4950);
DISPLAY INVISIBLE (-5875 4950);
FORCEPROP 1 LAST HDL_TAP TRUE
J 2
(-6200 4775);
DISPLAY 0.872340 (-6200 4775);
DISPLAY INVISIBLE (-6200 4775);
FORCEPROP 1 LAST PATH I267
J 2
(-5873 4900);
DISPLAY 0.872340 (-5873 4900);
PAINT GREEN (-5873 4900);
DISPLAY INVISIBLE (-5873 4900);
FORCEADD TAP..1
R 2
(-5875 5050);
FORCEPROP 3 LASTPIN (-5825 5050) SIG_NAME M_J_CPU0_SA_DQS_DN<9>
J 0
(-5815 5060);
DISPLAY 0.659574 (-5815 5060);
PAINT MONO (-5815 5060);
DISPLAY INVISIBLE (-5815 5060);
FORCEPROP 1 LASTPIN (-5825 5050) BN 9
J 2
(-5813 5058);
DISPLAY 0.489362 (-5813 5058);
PAINT GREEN (-5813 5058);
FORCEPROP 2 LAST CDS_LIB mstr_standard
J 2
(-5875 5050);
DISPLAY 0.723404 (-5875 5050);
PAINT MONO (-5875 5050);
DISPLAY INVISIBLE (-5875 5050);
FORCEPROP 1 LAST BODY_TYPE PLUMBING
J 2
(-5875 5100);
DISPLAY 0.872340 (-5875 5100);
PAINT GREEN (-5875 5100);
DISPLAY INVISIBLE (-5875 5100);
FORCEPROP 1 LAST HDL_TAP TRUE
J 2
(-6200 4925);
DISPLAY 0.872340 (-6200 4925);
DISPLAY INVISIBLE (-6200 4925);
FORCEPROP 1 LAST PATH I268
J 2
(-5873 5050);
DISPLAY 0.872340 (-5873 5050);
PAINT GREEN (-5873 5050);
DISPLAY INVISIBLE (-5873 5050);
FORCEADD TAP..1
R 2
(-5875 4800);
FORCEPROP 3 LASTPIN (-5825 4800) SIG_NAME M_J_CPU0_SB_DQS_DN<1>
J 0
(-5815 4810);
DISPLAY 0.659574 (-5815 4810);
PAINT MONO (-5815 4810);
DISPLAY INVISIBLE (-5815 4810);
FORCEPROP 1 LASTPIN (-5825 4800) BN 1
J 2
(-5813 4808);
DISPLAY 0.489362 (-5813 4808);
PAINT GREEN (-5813 4808);
FORCEPROP 2 LAST CDS_LIB mstr_standard
J 2
(-5875 4800);
DISPLAY 0.723404 (-5875 4800);
PAINT MONO (-5875 4800);
DISPLAY INVISIBLE (-5875 4800);
FORCEPROP 1 LAST BODY_TYPE PLUMBING
J 2
(-5875 4850);
DISPLAY 0.872340 (-5875 4850);
PAINT GREEN (-5875 4850);
DISPLAY INVISIBLE (-5875 4850);
FORCEPROP 1 LAST HDL_TAP TRUE
J 2
(-6200 4675);
DISPLAY 0.872340 (-6200 4675);
DISPLAY INVISIBLE (-6200 4675);
FORCEPROP 1 LAST PATH I269
J 2
(-5873 4800);
DISPLAY 0.872340 (-5873 4800);
PAINT GREEN (-5873 4800);
DISPLAY INVISIBLE (-5873 4800);
FORCEADD TAP..1
R 2
(-5875 4700);
FORCEPROP 3 LASTPIN (-5825 4700) SIG_NAME M_J_CPU0_SB_DQS_DN<2>
J 0
(-5815 4710);
DISPLAY 0.659574 (-5815 4710);
PAINT MONO (-5815 4710);
DISPLAY INVISIBLE (-5815 4710);
FORCEPROP 1 LASTPIN (-5825 4700) BN 2
J 2
(-5813 4708);
DISPLAY 0.489362 (-5813 4708);
PAINT GREEN (-5813 4708);
FORCEPROP 2 LAST CDS_LIB mstr_standard
J 2
(-5875 4700);
DISPLAY 0.723404 (-5875 4700);
PAINT MONO (-5875 4700);
DISPLAY INVISIBLE (-5875 4700);
FORCEPROP 1 LAST BODY_TYPE PLUMBING
J 2
(-5875 4750);
DISPLAY 0.872340 (-5875 4750);
PAINT GREEN (-5875 4750);
DISPLAY INVISIBLE (-5875 4750);
FORCEPROP 1 LAST HDL_TAP TRUE
J 2
(-6200 4575);
DISPLAY 0.872340 (-6200 4575);
DISPLAY INVISIBLE (-6200 4575);
FORCEPROP 1 LAST PATH I270
J 2
(-5873 4700);
DISPLAY 0.872340 (-5873 4700);
PAINT GREEN (-5873 4700);
DISPLAY INVISIBLE (-5873 4700);
FORCEADD TAP..1
R 2
(-5675 4550);
FORCEPROP 3 LASTPIN (-5625 4550) SIG_NAME M_J_CPU0_SB_DQS_DP<4>
J 0
(-5615 4560);
DISPLAY 0.659574 (-5615 4560);
PAINT MONO (-5615 4560);
DISPLAY INVISIBLE (-5615 4560);
FORCEPROP 1 LASTPIN (-5625 4550) BN 4
J 2
(-5613 4558);
DISPLAY 0.489362 (-5613 4558);
PAINT GREEN (-5613 4558);
FORCEPROP 2 LAST CDS_LIB mstr_standard
J 2
(-5675 4550);
DISPLAY 0.723404 (-5675 4550);
PAINT MONO (-5675 4550);
DISPLAY INVISIBLE (-5675 4550);
FORCEPROP 1 LAST BODY_TYPE PLUMBING
J 2
(-5675 4600);
DISPLAY 0.872340 (-5675 4600);
PAINT GREEN (-5675 4600);
DISPLAY INVISIBLE (-5675 4600);
FORCEPROP 1 LAST HDL_TAP TRUE
J 2
(-6000 4425);
DISPLAY 0.872340 (-6000 4425);
DISPLAY INVISIBLE (-6000 4425);
FORCEPROP 1 LAST PATH I271
J 2
(-5673 4550);
DISPLAY 0.872340 (-5673 4550);
PAINT GREEN (-5673 4550);
DISPLAY INVISIBLE (-5673 4550);
FORCEADD TAP..1
R 2
(-5675 4450);
FORCEPROP 3 LASTPIN (-5625 4450) SIG_NAME M_J_CPU0_SB_DQS_DP<5>
J 0
(-5615 4460);
DISPLAY 0.659574 (-5615 4460);
PAINT MONO (-5615 4460);
DISPLAY INVISIBLE (-5615 4460);
FORCEPROP 1 LASTPIN (-5625 4450) BN 5
J 2
(-5613 4458);
DISPLAY 0.489362 (-5613 4458);
PAINT GREEN (-5613 4458);
FORCEPROP 2 LAST CDS_LIB mstr_standard
J 2
(-5675 4450);
DISPLAY 0.723404 (-5675 4450);
PAINT MONO (-5675 4450);
DISPLAY INVISIBLE (-5675 4450);
FORCEPROP 1 LAST BODY_TYPE PLUMBING
J 2
(-5675 4500);
DISPLAY 0.872340 (-5675 4500);
PAINT GREEN (-5675 4500);
DISPLAY INVISIBLE (-5675 4500);
FORCEPROP 1 LAST HDL_TAP TRUE
J 2
(-6000 4325);
DISPLAY 0.872340 (-6000 4325);
DISPLAY INVISIBLE (-6000 4325);
FORCEPROP 1 LAST PATH I272
J 2
(-5673 4450);
DISPLAY 0.872340 (-5673 4450);
PAINT GREEN (-5673 4450);
DISPLAY INVISIBLE (-5673 4450);
FORCEADD TAP..1
R 2
(-5875 4600);
FORCEPROP 3 LASTPIN (-5825 4600) SIG_NAME M_J_CPU0_SB_DQS_DN<3>
J 0
(-5815 4610);
DISPLAY 0.659574 (-5815 4610);
PAINT MONO (-5815 4610);
DISPLAY INVISIBLE (-5815 4610);
FORCEPROP 1 LASTPIN (-5825 4600) BN 3
J 2
(-5813 4608);
DISPLAY 0.489362 (-5813 4608);
PAINT GREEN (-5813 4608);
FORCEPROP 2 LAST CDS_LIB mstr_standard
J 2
(-5875 4600);
DISPLAY 0.723404 (-5875 4600);
PAINT MONO (-5875 4600);
DISPLAY INVISIBLE (-5875 4600);
FORCEPROP 1 LAST BODY_TYPE PLUMBING
J 2
(-5875 4650);
DISPLAY 0.872340 (-5875 4650);
PAINT GREEN (-5875 4650);
DISPLAY INVISIBLE (-5875 4650);
FORCEPROP 1 LAST HDL_TAP TRUE
J 2
(-6200 4475);
DISPLAY 0.872340 (-6200 4475);
DISPLAY INVISIBLE (-6200 4475);
FORCEPROP 1 LAST PATH I273
J 2
(-5873 4600);
DISPLAY 0.872340 (-5873 4600);
PAINT GREEN (-5873 4600);
DISPLAY INVISIBLE (-5873 4600);
FORCEADD TAP..1
R 2
(-5675 4350);
FORCEPROP 3 LASTPIN (-5625 4350) SIG_NAME M_J_CPU0_SB_DQS_DP<6>
J 0
(-5615 4360);
DISPLAY 0.659574 (-5615 4360);
PAINT MONO (-5615 4360);
DISPLAY INVISIBLE (-5615 4360);
FORCEPROP 1 LASTPIN (-5625 4350) BN 6
J 2
(-5613 4358);
DISPLAY 0.489362 (-5613 4358);
PAINT GREEN (-5613 4358);
FORCEPROP 2 LAST CDS_LIB mstr_standard
J 2
(-5675 4350);
DISPLAY 0.723404 (-5675 4350);
PAINT MONO (-5675 4350);
DISPLAY INVISIBLE (-5675 4350);
FORCEPROP 1 LAST BODY_TYPE PLUMBING
J 2
(-5675 4400);
DISPLAY 0.872340 (-5675 4400);
PAINT GREEN (-5675 4400);
DISPLAY INVISIBLE (-5675 4400);
FORCEPROP 1 LAST HDL_TAP TRUE
J 2
(-6000 4225);
DISPLAY 0.872340 (-6000 4225);
DISPLAY INVISIBLE (-6000 4225);
FORCEPROP 1 LAST PATH I274
J 2
(-5673 4350);
DISPLAY 0.872340 (-5673 4350);
PAINT GREEN (-5673 4350);
DISPLAY INVISIBLE (-5673 4350);
FORCEADD TAP..1
R 2
(-5675 4250);
FORCEPROP 3 LASTPIN (-5625 4250) SIG_NAME M_J_CPU0_SB_DQS_DP<7>
J 0
(-5615 4260);
DISPLAY 0.659574 (-5615 4260);
PAINT MONO (-5615 4260);
DISPLAY INVISIBLE (-5615 4260);
FORCEPROP 1 LASTPIN (-5625 4250) BN 7
J 2
(-5613 4258);
DISPLAY 0.489362 (-5613 4258);
PAINT GREEN (-5613 4258);
FORCEPROP 2 LAST CDS_LIB mstr_standard
J 2
(-5675 4250);
DISPLAY 0.723404 (-5675 4250);
PAINT MONO (-5675 4250);
DISPLAY INVISIBLE (-5675 4250);
FORCEPROP 1 LAST BODY_TYPE PLUMBING
J 2
(-5675 4300);
DISPLAY 0.872340 (-5675 4300);
PAINT GREEN (-5675 4300);
DISPLAY INVISIBLE (-5675 4300);
FORCEPROP 1 LAST HDL_TAP TRUE
J 2
(-6000 4125);
DISPLAY 0.872340 (-6000 4125);
DISPLAY INVISIBLE (-6000 4125);
FORCEPROP 1 LAST PATH I275
J 2
(-5673 4250);
DISPLAY 0.872340 (-5673 4250);
PAINT GREEN (-5673 4250);
DISPLAY INVISIBLE (-5673 4250);
FORCEADD TAP..1
R 2
(-5675 4150);
FORCEPROP 3 LASTPIN (-5625 4150) SIG_NAME M_J_CPU0_SB_DQS_DP<8>
J 0
(-5615 4160);
DISPLAY 0.659574 (-5615 4160);
PAINT MONO (-5615 4160);
DISPLAY INVISIBLE (-5615 4160);
FORCEPROP 1 LASTPIN (-5625 4150) BN 8
J 2
(-5613 4158);
DISPLAY 0.489362 (-5613 4158);
PAINT GREEN (-5613 4158);
FORCEPROP 2 LAST CDS_LIB mstr_standard
J 2
(-5675 4150);
DISPLAY 0.723404 (-5675 4150);
PAINT MONO (-5675 4150);
DISPLAY INVISIBLE (-5675 4150);
FORCEPROP 1 LAST BODY_TYPE PLUMBING
J 2
(-5675 4200);
DISPLAY 0.872340 (-5675 4200);
PAINT GREEN (-5675 4200);
DISPLAY INVISIBLE (-5675 4200);
FORCEPROP 1 LAST HDL_TAP TRUE
J 2
(-6000 4025);
DISPLAY 0.872340 (-6000 4025);
DISPLAY INVISIBLE (-6000 4025);
FORCEPROP 1 LAST PATH I276
J 2
(-5673 4150);
DISPLAY 0.872340 (-5673 4150);
PAINT GREEN (-5673 4150);
DISPLAY INVISIBLE (-5673 4150);
FORCEADD TAP..1
R 2
(-5875 4400);
FORCEPROP 3 LASTPIN (-5825 4400) SIG_NAME M_J_CPU0_SB_DQS_DN<5>
J 0
(-5815 4410);
DISPLAY 0.659574 (-5815 4410);
PAINT MONO (-5815 4410);
DISPLAY INVISIBLE (-5815 4410);
FORCEPROP 1 LASTPIN (-5825 4400) BN 5
J 2
(-5813 4408);
DISPLAY 0.489362 (-5813 4408);
PAINT GREEN (-5813 4408);
FORCEPROP 2 LAST CDS_LIB mstr_standard
J 2
(-5875 4400);
DISPLAY 0.723404 (-5875 4400);
PAINT MONO (-5875 4400);
DISPLAY INVISIBLE (-5875 4400);
FORCEPROP 1 LAST BODY_TYPE PLUMBING
J 2
(-5875 4450);
DISPLAY 0.872340 (-5875 4450);
PAINT GREEN (-5875 4450);
DISPLAY INVISIBLE (-5875 4450);
FORCEPROP 1 LAST HDL_TAP TRUE
J 2
(-6200 4275);
DISPLAY 0.872340 (-6200 4275);
DISPLAY INVISIBLE (-6200 4275);
FORCEPROP 1 LAST PATH I277
J 2
(-5873 4400);
DISPLAY 0.872340 (-5873 4400);
PAINT GREEN (-5873 4400);
DISPLAY INVISIBLE (-5873 4400);
FORCEADD TAP..1
R 2
(-5875 4500);
FORCEPROP 3 LASTPIN (-5825 4500) SIG_NAME M_J_CPU0_SB_DQS_DN<4>
J 0
(-5815 4510);
DISPLAY 0.659574 (-5815 4510);
PAINT MONO (-5815 4510);
DISPLAY INVISIBLE (-5815 4510);
FORCEPROP 1 LASTPIN (-5825 4500) BN 4
J 2
(-5813 4508);
DISPLAY 0.489362 (-5813 4508);
PAINT GREEN (-5813 4508);
FORCEPROP 2 LAST CDS_LIB mstr_standard
J 2
(-5875 4500);
DISPLAY 0.723404 (-5875 4500);
PAINT MONO (-5875 4500);
DISPLAY INVISIBLE (-5875 4500);
FORCEPROP 1 LAST BODY_TYPE PLUMBING
J 2
(-5875 4550);
DISPLAY 0.872340 (-5875 4550);
PAINT GREEN (-5875 4550);
DISPLAY INVISIBLE (-5875 4550);
FORCEPROP 1 LAST HDL_TAP TRUE
J 2
(-6200 4375);
DISPLAY 0.872340 (-6200 4375);
DISPLAY INVISIBLE (-6200 4375);
FORCEPROP 1 LAST PATH I278
J 2
(-5873 4500);
DISPLAY 0.872340 (-5873 4500);
PAINT GREEN (-5873 4500);
DISPLAY INVISIBLE (-5873 4500);
FORCEADD TAP..1
R 2
(-5875 4100);
FORCEPROP 3 LASTPIN (-5825 4100) SIG_NAME M_J_CPU0_SB_DQS_DN<8>
J 0
(-5815 4110);
DISPLAY 0.659574 (-5815 4110);
PAINT MONO (-5815 4110);
DISPLAY INVISIBLE (-5815 4110);
FORCEPROP 1 LASTPIN (-5825 4100) BN 8
J 2
(-5813 4108);
DISPLAY 0.489362 (-5813 4108);
PAINT GREEN (-5813 4108);
FORCEPROP 2 LAST CDS_LIB mstr_standard
J 2
(-5875 4100);
DISPLAY 0.723404 (-5875 4100);
PAINT MONO (-5875 4100);
DISPLAY INVISIBLE (-5875 4100);
FORCEPROP 1 LAST BODY_TYPE PLUMBING
J 2
(-5875 4150);
DISPLAY 0.872340 (-5875 4150);
PAINT GREEN (-5875 4150);
DISPLAY INVISIBLE (-5875 4150);
FORCEPROP 1 LAST HDL_TAP TRUE
J 2
(-6200 3975);
DISPLAY 0.872340 (-6200 3975);
DISPLAY INVISIBLE (-6200 3975);
FORCEPROP 1 LAST PATH I279
J 2
(-5873 4100);
DISPLAY 0.872340 (-5873 4100);
PAINT GREEN (-5873 4100);
DISPLAY INVISIBLE (-5873 4100);
FORCEADD TAP..1
R 2
(-5875 4200);
FORCEPROP 3 LASTPIN (-5825 4200) SIG_NAME M_J_CPU0_SB_DQS_DN<7>
J 0
(-5815 4210);
DISPLAY 0.659574 (-5815 4210);
PAINT MONO (-5815 4210);
DISPLAY INVISIBLE (-5815 4210);
FORCEPROP 1 LASTPIN (-5825 4200) BN 7
J 2
(-5813 4208);
DISPLAY 0.489362 (-5813 4208);
PAINT GREEN (-5813 4208);
FORCEPROP 2 LAST CDS_LIB mstr_standard
J 2
(-5875 4200);
DISPLAY 0.723404 (-5875 4200);
PAINT MONO (-5875 4200);
DISPLAY INVISIBLE (-5875 4200);
FORCEPROP 1 LAST BODY_TYPE PLUMBING
J 2
(-5875 4250);
DISPLAY 0.872340 (-5875 4250);
PAINT GREEN (-5875 4250);
DISPLAY INVISIBLE (-5875 4250);
FORCEPROP 1 LAST HDL_TAP TRUE
J 2
(-6200 4075);
DISPLAY 0.872340 (-6200 4075);
DISPLAY INVISIBLE (-6200 4075);
FORCEPROP 1 LAST PATH I280
J 2
(-5873 4200);
DISPLAY 0.872340 (-5873 4200);
PAINT GREEN (-5873 4200);
DISPLAY INVISIBLE (-5873 4200);
FORCEADD TAP..1
R 2
(-5875 4300);
FORCEPROP 3 LASTPIN (-5825 4300) SIG_NAME M_J_CPU0_SB_DQS_DN<6>
J 0
(-5815 4310);
DISPLAY 0.659574 (-5815 4310);
PAINT MONO (-5815 4310);
DISPLAY INVISIBLE (-5815 4310);
FORCEPROP 1 LASTPIN (-5825 4300) BN 6
J 2
(-5813 4308);
DISPLAY 0.489362 (-5813 4308);
PAINT GREEN (-5813 4308);
FORCEPROP 2 LAST CDS_LIB mstr_standard
J 2
(-5875 4300);
DISPLAY 0.723404 (-5875 4300);
PAINT MONO (-5875 4300);
DISPLAY INVISIBLE (-5875 4300);
FORCEPROP 1 LAST BODY_TYPE PLUMBING
J 2
(-5875 4350);
DISPLAY 0.872340 (-5875 4350);
PAINT GREEN (-5875 4350);
DISPLAY INVISIBLE (-5875 4350);
FORCEPROP 1 LAST HDL_TAP TRUE
J 2
(-6200 4175);
DISPLAY 0.872340 (-6200 4175);
DISPLAY INVISIBLE (-6200 4175);
FORCEPROP 1 LAST PATH I281
J 2
(-5873 4300);
DISPLAY 0.872340 (-5873 4300);
PAINT GREEN (-5873 4300);
DISPLAY INVISIBLE (-5873 4300);
FORCEADD OFFPAGE..3
R 2
(-6575 6025);
FORCEPROP 2 LAST $XR0 94 
J 0
(-6854 6025);
DISPLAY 0.638298 (-6854 6025);
PAINT MONO (-6854 6025);
FORCEPROP 2 LAST PATH I282
J 0
(-6875 6075);
DISPLAY 1.021277 (-6875 6075);
DISPLAY INVISIBLE (-6875 6075);
FORCEPROP 1 LAST COMMENT_BODY TRUE
J 2
(-6525 5925);
DISPLAY 0.872340 (-6525 5925);
PAINT GREEN (-6525 5925);
DISPLAY INVISIBLE (-6525 5925);
FORCEPROP 1 LAST OFFPAGE TRUE
J 2
(-6900 5900);
DISPLAY 0.872340 (-6900 5900);
PAINT GREEN (-6900 5900);
DISPLAY INVISIBLE (-6900 5900);
FORCEPROP 2 LAST CDS_LIB standard
J 0
(-6575 6025);
DISPLAY INVISIBLE (-6575 6025);
FORCEADD OFFPAGE..3
R 2
(-6575 5975);
FORCEPROP 2 LAST $XR0 94 
J 0
(-6854 5975);
DISPLAY 0.638298 (-6854 5975);
PAINT MONO (-6854 5975);
FORCEPROP 2 LAST PATH I283
J 0
(-6875 6025);
DISPLAY 1.021277 (-6875 6025);
DISPLAY INVISIBLE (-6875 6025);
FORCEPROP 1 LAST COMMENT_BODY TRUE
J 2
(-6525 5875);
DISPLAY 0.872340 (-6525 5875);
PAINT GREEN (-6525 5875);
DISPLAY INVISIBLE (-6525 5875);
FORCEPROP 1 LAST OFFPAGE TRUE
J 2
(-6900 5850);
DISPLAY 0.872340 (-6900 5850);
PAINT GREEN (-6900 5850);
DISPLAY INVISIBLE (-6900 5850);
FORCEPROP 2 LAST CDS_LIB standard
J 0
(-6575 5975);
DISPLAY INVISIBLE (-6575 5975);
FORCEADD OFFPAGE..3
R 2
(-6575 4975);
FORCEPROP 2 LAST $XR0 94 
J 0
(-6854 4975);
DISPLAY 0.638298 (-6854 4975);
PAINT MONO (-6854 4975);
FORCEPROP 2 LAST PATH I284
J 0
(-6875 5025);
DISPLAY 1.021277 (-6875 5025);
DISPLAY INVISIBLE (-6875 5025);
FORCEPROP 1 LAST COMMENT_BODY TRUE
J 2
(-6525 4875);
DISPLAY 0.872340 (-6525 4875);
PAINT GREEN (-6525 4875);
DISPLAY INVISIBLE (-6525 4875);
FORCEPROP 1 LAST OFFPAGE TRUE
J 2
(-6900 4850);
DISPLAY 0.872340 (-6900 4850);
PAINT GREEN (-6900 4850);
DISPLAY INVISIBLE (-6900 4850);
FORCEPROP 2 LAST CDS_LIB standard
J 0
(-6575 4975);
DISPLAY INVISIBLE (-6575 4975);
FORCEADD OFFPAGE..3
R 2
(-6575 4925);
FORCEPROP 2 LAST $XR0 94 
J 0
(-6854 4925);
DISPLAY 0.638298 (-6854 4925);
PAINT MONO (-6854 4925);
FORCEPROP 2 LAST PATH I285
J 0
(-6875 4975);
DISPLAY 1.021277 (-6875 4975);
DISPLAY INVISIBLE (-6875 4975);
FORCEPROP 1 LAST COMMENT_BODY TRUE
J 2
(-6525 4825);
DISPLAY 0.872340 (-6525 4825);
PAINT GREEN (-6525 4825);
DISPLAY INVISIBLE (-6525 4825);
FORCEPROP 1 LAST OFFPAGE TRUE
J 2
(-6900 4800);
DISPLAY 0.872340 (-6900 4800);
PAINT GREEN (-6900 4800);
DISPLAY INVISIBLE (-6900 4800);
FORCEPROP 2 LAST CDS_LIB standard
J 0
(-6575 4925);
DISPLAY INVISIBLE (-6575 4925);
FORCEADD TAP..1
R 2
(-5675 4050);
FORCEPROP 3 LASTPIN (-5625 4050) SIG_NAME M_J_CPU0_SB_DQS_DP<9>
J 0
(-5615 4060);
DISPLAY 0.659574 (-5615 4060);
PAINT MONO (-5615 4060);
DISPLAY INVISIBLE (-5615 4060);
FORCEPROP 1 LASTPIN (-5625 4050) BN 9
J 2
(-5613 4058);
DISPLAY 0.489362 (-5613 4058);
PAINT GREEN (-5613 4058);
FORCEPROP 2 LAST CDS_LIB mstr_standard
J 2
(-5675 4050);
DISPLAY 0.723404 (-5675 4050);
PAINT MONO (-5675 4050);
DISPLAY INVISIBLE (-5675 4050);
FORCEPROP 1 LAST BODY_TYPE PLUMBING
J 2
(-5675 4100);
DISPLAY 0.872340 (-5675 4100);
PAINT GREEN (-5675 4100);
DISPLAY INVISIBLE (-5675 4100);
FORCEPROP 1 LAST HDL_TAP TRUE
J 2
(-6000 3925);
DISPLAY 0.872340 (-6000 3925);
DISPLAY INVISIBLE (-6000 3925);
FORCEPROP 1 LAST PATH I286
J 2
(-5673 4050);
DISPLAY 0.872340 (-5673 4050);
PAINT GREEN (-5673 4050);
DISPLAY INVISIBLE (-5673 4050);
FORCEADD TAP..1
R 2
(-5875 3850);
FORCEPROP 3 LASTPIN (-5825 3850) SIG_NAME M_J_CPU0_SA_CA<0>
J 0
(-5815 3860);
DISPLAY 0.659574 (-5815 3860);
PAINT MONO (-5815 3860);
DISPLAY INVISIBLE (-5815 3860);
FORCEPROP 1 LASTPIN (-5825 3850) BN 0
J 2
(-5813 3858);
DISPLAY 0.489362 (-5813 3858);
PAINT GREEN (-5813 3858);
FORCEPROP 2 LAST CDS_LIB mstr_standard
J 0
(-5875 3850);
DISPLAY 0.723404 (-5875 3850);
PAINT MONO (-5875 3850);
DISPLAY INVISIBLE (-5875 3850);
FORCEPROP 1 LAST BODY_TYPE PLUMBING
J 2
(-5875 3900);
DISPLAY 0.872340 (-5875 3900);
PAINT GREEN (-5875 3900);
DISPLAY INVISIBLE (-5875 3900);
FORCEPROP 1 LAST HDL_TAP TRUE
J 2
(-6200 3725);
DISPLAY 0.872340 (-6200 3725);
DISPLAY INVISIBLE (-6200 3725);
FORCEPROP 1 LAST PATH I287
J 2
(-5873 3850);
DISPLAY 0.872340 (-5873 3850);
PAINT GREEN (-5873 3850);
DISPLAY INVISIBLE (-5873 3850);
FORCEADD TAP..1
R 2
(-5875 4000);
FORCEPROP 3 LASTPIN (-5825 4000) SIG_NAME M_J_CPU0_SB_DQS_DN<9>
J 0
(-5815 4010);
DISPLAY 0.659574 (-5815 4010);
PAINT MONO (-5815 4010);
DISPLAY INVISIBLE (-5815 4010);
FORCEPROP 1 LASTPIN (-5825 4000) BN 9
J 2
(-5813 4008);
DISPLAY 0.489362 (-5813 4008);
PAINT GREEN (-5813 4008);
FORCEPROP 2 LAST CDS_LIB mstr_standard
J 2
(-5875 4000);
DISPLAY 0.723404 (-5875 4000);
PAINT MONO (-5875 4000);
DISPLAY INVISIBLE (-5875 4000);
FORCEPROP 1 LAST BODY_TYPE PLUMBING
J 2
(-5875 4050);
DISPLAY 0.872340 (-5875 4050);
PAINT GREEN (-5875 4050);
DISPLAY INVISIBLE (-5875 4050);
FORCEPROP 1 LAST HDL_TAP TRUE
J 2
(-6200 3875);
DISPLAY 0.872340 (-6200 3875);
DISPLAY INVISIBLE (-6200 3875);
FORCEPROP 1 LAST PATH I288
J 2
(-5873 4000);
DISPLAY 0.872340 (-5873 4000);
PAINT GREEN (-5873 4000);
DISPLAY INVISIBLE (-5873 4000);
FORCEADD TAP..1
R 2
(-5875 3700);
FORCEPROP 3 LASTPIN (-5825 3700) SIG_NAME M_J_CPU0_SA_CA<3>
J 0
(-5815 3710);
DISPLAY 0.659574 (-5815 3710);
PAINT MONO (-5815 3710);
DISPLAY INVISIBLE (-5815 3710);
FORCEPROP 1 LASTPIN (-5825 3700) BN 3
J 2
(-5813 3708);
DISPLAY 0.489362 (-5813 3708);
PAINT GREEN (-5813 3708);
FORCEPROP 2 LAST CDS_LIB mstr_standard
J 0
(-5875 3700);
DISPLAY 0.723404 (-5875 3700);
PAINT MONO (-5875 3700);
DISPLAY INVISIBLE (-5875 3700);
FORCEPROP 1 LAST BODY_TYPE PLUMBING
J 2
(-5875 3750);
DISPLAY 0.872340 (-5875 3750);
PAINT GREEN (-5875 3750);
DISPLAY INVISIBLE (-5875 3750);
FORCEPROP 1 LAST HDL_TAP TRUE
J 2
(-6200 3575);
DISPLAY 0.872340 (-6200 3575);
DISPLAY INVISIBLE (-6200 3575);
FORCEPROP 1 LAST PATH I289
J 2
(-5873 3700);
DISPLAY 0.872340 (-5873 3700);
PAINT GREEN (-5873 3700);
DISPLAY INVISIBLE (-5873 3700);
FORCEADD TAP..1
R 2
(-5875 3750);
FORCEPROP 3 LASTPIN (-5825 3750) SIG_NAME M_J_CPU0_SA_CA<2>
J 0
(-5815 3760);
DISPLAY 0.659574 (-5815 3760);
PAINT MONO (-5815 3760);
DISPLAY INVISIBLE (-5815 3760);
FORCEPROP 1 LASTPIN (-5825 3750) BN 2
J 2
(-5813 3758);
DISPLAY 0.489362 (-5813 3758);
PAINT GREEN (-5813 3758);
FORCEPROP 2 LAST CDS_LIB mstr_standard
J 0
(-5875 3750);
DISPLAY 0.723404 (-5875 3750);
PAINT MONO (-5875 3750);
DISPLAY INVISIBLE (-5875 3750);
FORCEPROP 1 LAST BODY_TYPE PLUMBING
J 2
(-5875 3800);
DISPLAY 0.872340 (-5875 3800);
PAINT GREEN (-5875 3800);
DISPLAY INVISIBLE (-5875 3800);
FORCEPROP 1 LAST HDL_TAP TRUE
J 2
(-6200 3625);
DISPLAY 0.872340 (-6200 3625);
DISPLAY INVISIBLE (-6200 3625);
FORCEPROP 1 LAST PATH I290
J 2
(-5873 3750);
DISPLAY 0.872340 (-5873 3750);
PAINT GREEN (-5873 3750);
DISPLAY INVISIBLE (-5873 3750);
FORCEADD TAP..1
R 2
(-5875 3800);
FORCEPROP 3 LASTPIN (-5825 3800) SIG_NAME M_J_CPU0_SA_CA<1>
J 0
(-5815 3810);
DISPLAY 0.659574 (-5815 3810);
PAINT MONO (-5815 3810);
DISPLAY INVISIBLE (-5815 3810);
FORCEPROP 1 LASTPIN (-5825 3800) BN 1
J 2
(-5813 3808);
DISPLAY 0.489362 (-5813 3808);
PAINT GREEN (-5813 3808);
FORCEPROP 2 LAST CDS_LIB mstr_standard
J 0
(-5875 3800);
DISPLAY 0.723404 (-5875 3800);
PAINT MONO (-5875 3800);
DISPLAY INVISIBLE (-5875 3800);
FORCEPROP 1 LAST BODY_TYPE PLUMBING
J 2
(-5875 3850);
DISPLAY 0.872340 (-5875 3850);
PAINT GREEN (-5875 3850);
DISPLAY INVISIBLE (-5875 3850);
FORCEPROP 1 LAST HDL_TAP TRUE
J 2
(-6200 3675);
DISPLAY 0.872340 (-6200 3675);
DISPLAY INVISIBLE (-6200 3675);
FORCEPROP 1 LAST PATH I291
J 2
(-5873 3800);
DISPLAY 0.872340 (-5873 3800);
PAINT GREEN (-5873 3800);
DISPLAY INVISIBLE (-5873 3800);
FORCEADD TAP..1
R 2
(-5875 3650);
FORCEPROP 3 LASTPIN (-5825 3650) SIG_NAME M_J_CPU0_SA_CA<4>
J 0
(-5815 3660);
DISPLAY 0.659574 (-5815 3660);
PAINT MONO (-5815 3660);
DISPLAY INVISIBLE (-5815 3660);
FORCEPROP 1 LASTPIN (-5825 3650) BN 4
J 2
(-5813 3658);
DISPLAY 0.489362 (-5813 3658);
PAINT GREEN (-5813 3658);
FORCEPROP 2 LAST CDS_LIB mstr_standard
J 0
(-5875 3650);
DISPLAY 0.723404 (-5875 3650);
PAINT MONO (-5875 3650);
DISPLAY INVISIBLE (-5875 3650);
FORCEPROP 1 LAST BODY_TYPE PLUMBING
J 2
(-5875 3700);
DISPLAY 0.872340 (-5875 3700);
PAINT GREEN (-5875 3700);
DISPLAY INVISIBLE (-5875 3700);
FORCEPROP 1 LAST HDL_TAP TRUE
J 2
(-6200 3525);
DISPLAY 0.872340 (-6200 3525);
DISPLAY INVISIBLE (-6200 3525);
FORCEPROP 1 LAST PATH I292
J 2
(-5873 3650);
DISPLAY 0.872340 (-5873 3650);
PAINT GREEN (-5873 3650);
DISPLAY INVISIBLE (-5873 3650);
FORCEADD TAP..1
R 2
(-5875 3600);
FORCEPROP 3 LASTPIN (-5825 3600) SIG_NAME M_J_CPU0_SA_CA<5>
J 0
(-5815 3610);
DISPLAY 0.659574 (-5815 3610);
PAINT MONO (-5815 3610);
DISPLAY INVISIBLE (-5815 3610);
FORCEPROP 1 LASTPIN (-5825 3600) BN 5
J 2
(-5813 3608);
DISPLAY 0.489362 (-5813 3608);
PAINT GREEN (-5813 3608);
FORCEPROP 2 LAST CDS_LIB mstr_standard
J 0
(-5875 3600);
DISPLAY 0.723404 (-5875 3600);
PAINT MONO (-5875 3600);
DISPLAY INVISIBLE (-5875 3600);
FORCEPROP 1 LAST BODY_TYPE PLUMBING
J 2
(-5875 3650);
DISPLAY 0.872340 (-5875 3650);
PAINT GREEN (-5875 3650);
DISPLAY INVISIBLE (-5875 3650);
FORCEPROP 1 LAST HDL_TAP TRUE
J 2
(-6200 3475);
DISPLAY 0.872340 (-6200 3475);
DISPLAY INVISIBLE (-6200 3475);
FORCEPROP 1 LAST PATH I293
J 2
(-5873 3600);
DISPLAY 0.872340 (-5873 3600);
PAINT GREEN (-5873 3600);
DISPLAY INVISIBLE (-5873 3600);
FORCEADD TAP..1
R 2
(-5875 3400);
FORCEPROP 3 LASTPIN (-5825 3400) SIG_NAME M_J_CPU0_SB_CA<1>
J 0
(-5815 3410);
DISPLAY 0.659574 (-5815 3410);
PAINT MONO (-5815 3410);
DISPLAY INVISIBLE (-5815 3410);
FORCEPROP 1 LASTPIN (-5825 3400) BN 1
J 2
(-5813 3408);
DISPLAY 0.489362 (-5813 3408);
PAINT GREEN (-5813 3408);
FORCEPROP 2 LAST CDS_LIB mstr_standard
J 0
(-5875 3400);
DISPLAY 0.723404 (-5875 3400);
PAINT MONO (-5875 3400);
DISPLAY INVISIBLE (-5875 3400);
FORCEPROP 1 LAST BODY_TYPE PLUMBING
J 2
(-5875 3450);
DISPLAY 0.872340 (-5875 3450);
PAINT GREEN (-5875 3450);
DISPLAY INVISIBLE (-5875 3450);
FORCEPROP 1 LAST HDL_TAP TRUE
J 2
(-6200 3275);
DISPLAY 0.872340 (-6200 3275);
DISPLAY INVISIBLE (-6200 3275);
FORCEPROP 1 LAST PATH I294
J 2
(-5873 3400);
DISPLAY 0.872340 (-5873 3400);
PAINT GREEN (-5873 3400);
DISPLAY INVISIBLE (-5873 3400);
FORCEADD TAP..1
R 2
(-5875 3350);
FORCEPROP 3 LASTPIN (-5825 3350) SIG_NAME M_J_CPU0_SB_CA<2>
J 0
(-5815 3360);
DISPLAY 0.659574 (-5815 3360);
PAINT MONO (-5815 3360);
DISPLAY INVISIBLE (-5815 3360);
FORCEPROP 1 LASTPIN (-5825 3350) BN 2
J 2
(-5813 3358);
DISPLAY 0.489362 (-5813 3358);
PAINT GREEN (-5813 3358);
FORCEPROP 2 LAST CDS_LIB mstr_standard
J 0
(-5875 3350);
DISPLAY 0.723404 (-5875 3350);
PAINT MONO (-5875 3350);
DISPLAY INVISIBLE (-5875 3350);
FORCEPROP 1 LAST BODY_TYPE PLUMBING
J 2
(-5875 3400);
DISPLAY 0.872340 (-5875 3400);
PAINT GREEN (-5875 3400);
DISPLAY INVISIBLE (-5875 3400);
FORCEPROP 1 LAST HDL_TAP TRUE
J 2
(-6200 3225);
DISPLAY 0.872340 (-6200 3225);
DISPLAY INVISIBLE (-6200 3225);
FORCEPROP 1 LAST PATH I295
J 2
(-5873 3350);
DISPLAY 0.872340 (-5873 3350);
PAINT GREEN (-5873 3350);
DISPLAY INVISIBLE (-5873 3350);
FORCEADD TAP..1
R 2
(-5875 3450);
FORCEPROP 3 LASTPIN (-5825 3450) SIG_NAME M_J_CPU0_SB_CA<0>
J 0
(-5815 3460);
DISPLAY 0.659574 (-5815 3460);
PAINT MONO (-5815 3460);
DISPLAY INVISIBLE (-5815 3460);
FORCEPROP 1 LASTPIN (-5825 3450) BN 0
J 2
(-5813 3458);
DISPLAY 0.489362 (-5813 3458);
PAINT GREEN (-5813 3458);
FORCEPROP 2 LAST CDS_LIB mstr_standard
J 0
(-5875 3450);
DISPLAY 0.723404 (-5875 3450);
PAINT MONO (-5875 3450);
DISPLAY INVISIBLE (-5875 3450);
FORCEPROP 1 LAST BODY_TYPE PLUMBING
J 2
(-5875 3500);
DISPLAY 0.872340 (-5875 3500);
PAINT GREEN (-5875 3500);
DISPLAY INVISIBLE (-5875 3500);
FORCEPROP 1 LAST HDL_TAP TRUE
J 2
(-6200 3325);
DISPLAY 0.872340 (-6200 3325);
DISPLAY INVISIBLE (-6200 3325);
FORCEPROP 1 LAST PATH I296
J 2
(-5873 3450);
DISPLAY 0.872340 (-5873 3450);
PAINT GREEN (-5873 3450);
DISPLAY INVISIBLE (-5873 3450);
FORCEADD TAP..1
R 2
(-5875 3550);
FORCEPROP 3 LASTPIN (-5825 3550) SIG_NAME M_J_CPU0_SA_CA<6>
J 0
(-5815 3560);
DISPLAY 0.659574 (-5815 3560);
PAINT MONO (-5815 3560);
DISPLAY INVISIBLE (-5815 3560);
FORCEPROP 1 LASTPIN (-5825 3550) BN 6
J 2
(-5813 3558);
DISPLAY 0.489362 (-5813 3558);
PAINT GREEN (-5813 3558);
FORCEPROP 2 LAST CDS_LIB mstr_standard
J 0
(-5875 3550);
DISPLAY 0.723404 (-5875 3550);
PAINT MONO (-5875 3550);
DISPLAY INVISIBLE (-5875 3550);
FORCEPROP 1 LAST BODY_TYPE PLUMBING
J 2
(-5875 3600);
DISPLAY 0.872340 (-5875 3600);
PAINT GREEN (-5875 3600);
DISPLAY INVISIBLE (-5875 3600);
FORCEPROP 1 LAST HDL_TAP TRUE
J 2
(-6200 3425);
DISPLAY 0.872340 (-6200 3425);
DISPLAY INVISIBLE (-6200 3425);
FORCEPROP 1 LAST PATH I297
J 2
(-5873 3550);
DISPLAY 0.872340 (-5873 3550);
PAINT GREEN (-5873 3550);
DISPLAY INVISIBLE (-5873 3550);
FORCEADD TAP..1
R 2
(-5875 3200);
FORCEPROP 3 LASTPIN (-5825 3200) SIG_NAME M_J_CPU0_SB_CA<5>
J 0
(-5815 3210);
DISPLAY 0.659574 (-5815 3210);
PAINT MONO (-5815 3210);
DISPLAY INVISIBLE (-5815 3210);
FORCEPROP 1 LASTPIN (-5825 3200) BN 5
J 2
(-5813 3208);
DISPLAY 0.489362 (-5813 3208);
PAINT GREEN (-5813 3208);
FORCEPROP 2 LAST CDS_LIB mstr_standard
J 0
(-5875 3200);
DISPLAY 0.723404 (-5875 3200);
PAINT MONO (-5875 3200);
DISPLAY INVISIBLE (-5875 3200);
FORCEPROP 1 LAST BODY_TYPE PLUMBING
J 2
(-5875 3250);
DISPLAY 0.872340 (-5875 3250);
PAINT GREEN (-5875 3250);
DISPLAY INVISIBLE (-5875 3250);
FORCEPROP 1 LAST HDL_TAP TRUE
J 2
(-6200 3075);
DISPLAY 0.872340 (-6200 3075);
DISPLAY INVISIBLE (-6200 3075);
FORCEPROP 1 LAST PATH I298
J 2
(-5873 3200);
DISPLAY 0.872340 (-5873 3200);
PAINT GREEN (-5873 3200);
DISPLAY INVISIBLE (-5873 3200);
FORCEADD TAP..1
R 2
(-5875 3150);
FORCEPROP 3 LASTPIN (-5825 3150) SIG_NAME M_J_CPU0_SB_CA<6>
J 0
(-5815 3160);
DISPLAY 0.659574 (-5815 3160);
PAINT MONO (-5815 3160);
DISPLAY INVISIBLE (-5815 3160);
FORCEPROP 1 LASTPIN (-5825 3150) BN 6
J 2
(-5813 3158);
DISPLAY 0.489362 (-5813 3158);
PAINT GREEN (-5813 3158);
FORCEPROP 2 LAST CDS_LIB mstr_standard
J 0
(-5875 3150);
DISPLAY 0.723404 (-5875 3150);
PAINT MONO (-5875 3150);
DISPLAY INVISIBLE (-5875 3150);
FORCEPROP 1 LAST BODY_TYPE PLUMBING
J 2
(-5875 3200);
DISPLAY 0.872340 (-5875 3200);
PAINT GREEN (-5875 3200);
DISPLAY INVISIBLE (-5875 3200);
FORCEPROP 1 LAST HDL_TAP TRUE
J 2
(-6200 3025);
DISPLAY 0.872340 (-6200 3025);
DISPLAY INVISIBLE (-6200 3025);
FORCEPROP 1 LAST PATH I299
J 2
(-5873 3150);
DISPLAY 0.872340 (-5873 3150);
PAINT GREEN (-5873 3150);
DISPLAY INVISIBLE (-5873 3150);
FORCEADD TAP..1
R 2
(-5875 3250);
FORCEPROP 3 LASTPIN (-5825 3250) SIG_NAME M_J_CPU0_SB_CA<4>
J 0
(-5815 3260);
DISPLAY 0.659574 (-5815 3260);
PAINT MONO (-5815 3260);
DISPLAY INVISIBLE (-5815 3260);
FORCEPROP 1 LASTPIN (-5825 3250) BN 4
J 2
(-5813 3258);
DISPLAY 0.489362 (-5813 3258);
PAINT GREEN (-5813 3258);
FORCEPROP 2 LAST CDS_LIB mstr_standard
J 0
(-5875 3250);
DISPLAY 0.723404 (-5875 3250);
PAINT MONO (-5875 3250);
DISPLAY INVISIBLE (-5875 3250);
FORCEPROP 1 LAST BODY_TYPE PLUMBING
J 2
(-5875 3300);
DISPLAY 0.872340 (-5875 3300);
PAINT GREEN (-5875 3300);
DISPLAY INVISIBLE (-5875 3300);
FORCEPROP 1 LAST HDL_TAP TRUE
J 2
(-6200 3125);
DISPLAY 0.872340 (-6200 3125);
DISPLAY INVISIBLE (-6200 3125);
FORCEPROP 1 LAST PATH I300
J 2
(-5873 3250);
DISPLAY 0.872340 (-5873 3250);
PAINT GREEN (-5873 3250);
DISPLAY INVISIBLE (-5873 3250);
FORCEADD TAP..1
R 2
(-5875 3300);
FORCEPROP 3 LASTPIN (-5825 3300) SIG_NAME M_J_CPU0_SB_CA<3>
J 0
(-5815 3310);
DISPLAY 0.659574 (-5815 3310);
PAINT MONO (-5815 3310);
DISPLAY INVISIBLE (-5815 3310);
FORCEPROP 1 LASTPIN (-5825 3300) BN 3
J 2
(-5813 3308);
DISPLAY 0.489362 (-5813 3308);
PAINT GREEN (-5813 3308);
FORCEPROP 2 LAST CDS_LIB mstr_standard
J 0
(-5875 3300);
DISPLAY 0.723404 (-5875 3300);
PAINT MONO (-5875 3300);
DISPLAY INVISIBLE (-5875 3300);
FORCEPROP 1 LAST BODY_TYPE PLUMBING
J 2
(-5875 3350);
DISPLAY 0.872340 (-5875 3350);
PAINT GREEN (-5875 3350);
DISPLAY INVISIBLE (-5875 3350);
FORCEPROP 1 LAST HDL_TAP TRUE
J 2
(-6200 3175);
DISPLAY 0.872340 (-6200 3175);
DISPLAY INVISIBLE (-6200 3175);
FORCEPROP 1 LAST PATH I301
J 2
(-5873 3300);
DISPLAY 0.872340 (-5873 3300);
PAINT GREEN (-5873 3300);
DISPLAY INVISIBLE (-5873 3300);
FORCEADD OFFPAGE..2
R 2
(-6475 3875);
FORCEPROP 2 LAST $XR0 94 
J 0
(-6729 3875);
DISPLAY 0.638298 (-6729 3875);
PAINT MONO (-6729 3875);
FORCEPROP 2 LAST PATH I302
J 0
(-6750 3925);
DISPLAY 1.021277 (-6750 3925);
DISPLAY INVISIBLE (-6750 3925);
FORCEPROP 1 LAST COMMENT_BODY TRUE
J 2
(-6430 3780);
DISPLAY 0.872340 (-6430 3780);
PAINT GREEN (-6430 3780);
DISPLAY INVISIBLE (-6430 3780);
FORCEPROP 1 LAST OFFPAGE TRUE
J 2
(-6800 3750);
DISPLAY 0.872340 (-6800 3750);
PAINT GREEN (-6800 3750);
DISPLAY INVISIBLE (-6800 3750);
FORCEPROP 2 LAST CDS_LIB standard
J 0
(-6475 3875);
DISPLAY INVISIBLE (-6475 3875);
FORCEADD OFFPAGE..2
R 2
(-6475 3475);
FORCEPROP 2 LAST $XR0 94 
J 0
(-6729 3475);
DISPLAY 0.638298 (-6729 3475);
PAINT MONO (-6729 3475);
FORCEPROP 2 LAST PATH I303
J 0
(-6750 3525);
DISPLAY 1.021277 (-6750 3525);
DISPLAY INVISIBLE (-6750 3525);
FORCEPROP 1 LAST COMMENT_BODY TRUE
J 2
(-6430 3380);
DISPLAY 0.872340 (-6430 3380);
PAINT GREEN (-6430 3380);
DISPLAY INVISIBLE (-6430 3380);
FORCEPROP 1 LAST OFFPAGE TRUE
J 2
(-6800 3350);
DISPLAY 0.872340 (-6800 3350);
PAINT GREEN (-6800 3350);
DISPLAY INVISIBLE (-6800 3350);
FORCEPROP 2 LAST CDS_LIB standard
J 0
(-6475 3475);
DISPLAY INVISIBLE (-6475 3475);
FORCEADD OFFPAGE..2
R 2
(-6475 3000);
FORCEPROP 2 LAST $XR0 94 
J 0
(-6729 3000);
DISPLAY 0.638298 (-6729 3000);
PAINT MONO (-6729 3000);
FORCEPROP 2 LAST PATH I304
J 0
(-6750 3050);
DISPLAY 1.021277 (-6750 3050);
DISPLAY INVISIBLE (-6750 3050);
FORCEPROP 1 LAST COMMENT_BODY TRUE
J 2
(-6430 2905);
DISPLAY 0.872340 (-6430 2905);
PAINT GREEN (-6430 2905);
DISPLAY INVISIBLE (-6430 2905);
FORCEPROP 1 LAST OFFPAGE TRUE
J 2
(-6800 2875);
DISPLAY 0.872340 (-6800 2875);
PAINT GREEN (-6800 2875);
DISPLAY INVISIBLE (-6800 2875);
FORCEPROP 2 LAST CDS_LIB standard
J 0
(-6475 3000);
DISPLAY INVISIBLE (-6475 3000);
FORCEADD OFFPAGE..2
R 2
(-6475 2950);
FORCEPROP 2 LAST $XR0 94 
J 0
(-6729 2950);
DISPLAY 0.638298 (-6729 2950);
PAINT MONO (-6729 2950);
FORCEPROP 2 LAST PATH I305
J 0
(-6750 3000);
DISPLAY 1.021277 (-6750 3000);
DISPLAY INVISIBLE (-6750 3000);
FORCEPROP 1 LAST COMMENT_BODY TRUE
J 2
(-6430 2855);
DISPLAY 0.872340 (-6430 2855);
PAINT GREEN (-6430 2855);
DISPLAY INVISIBLE (-6430 2855);
FORCEPROP 1 LAST OFFPAGE TRUE
J 2
(-6800 2825);
DISPLAY 0.872340 (-6800 2825);
PAINT GREEN (-6800 2825);
DISPLAY INVISIBLE (-6800 2825);
FORCEPROP 2 LAST CDS_LIB standard
J 0
(-6475 2950);
DISPLAY INVISIBLE (-6475 2950);
FORCEADD OFFPAGE..2
R 2
(-6475 2850);
FORCEPROP 2 LAST $XR0 94 
J 0
(-6729 2850);
DISPLAY 0.638298 (-6729 2850);
PAINT MONO (-6729 2850);
FORCEPROP 2 LAST PATH I306
J 0
(-6750 2900);
DISPLAY 1.021277 (-6750 2900);
DISPLAY INVISIBLE (-6750 2900);
FORCEPROP 1 LAST COMMENT_BODY TRUE
J 2
(-6430 2755);
DISPLAY 0.872340 (-6430 2755);
PAINT GREEN (-6430 2755);
DISPLAY INVISIBLE (-6430 2755);
FORCEPROP 1 LAST OFFPAGE TRUE
J 2
(-6800 2725);
DISPLAY 0.872340 (-6800 2725);
PAINT GREEN (-6800 2725);
DISPLAY INVISIBLE (-6800 2725);
FORCEPROP 2 LAST CDS_LIB standard
J 0
(-6475 2850);
DISPLAY INVISIBLE (-6475 2850);
FORCEADD OFFPAGE..5
(-6475 2600);
FORCEPROP 2 LAST $XR0 94 
J 0
(-6729 2600);
DISPLAY 0.638298 (-6729 2600);
PAINT MONO (-6729 2600);
FORCEPROP 2 LAST PATH I307
J 0
(-6750 2650);
DISPLAY 1.021277 (-6750 2650);
DISPLAY INVISIBLE (-6750 2650);
FORCEPROP 1 LAST COMMENT_BODY TRUE
J 0
(-6375 2525);
DISPLAY 0.872340 (-6375 2525);
PAINT GREEN (-6375 2525);
DISPLAY INVISIBLE (-6375 2525);
FORCEPROP 1 LAST OFFPAGE TRUE
J 0
(-6150 2475);
DISPLAY 0.872340 (-6150 2475);
PAINT GREEN (-6150 2475);
DISPLAY INVISIBLE (-6150 2475);
FORCEPROP 2 LAST CDS_LIB mstr_standard
J 0
(-6475 2600);
DISPLAY INVISIBLE (-6475 2600);
FORCEADD OFFPAGE..2
R 2
(-6475 2800);
FORCEPROP 2 LAST $XR0 94 
J 0
(-6729 2800);
DISPLAY 0.638298 (-6729 2800);
PAINT MONO (-6729 2800);
FORCEPROP 2 LAST PATH I308
J 0
(-6750 2850);
DISPLAY 1.021277 (-6750 2850);
DISPLAY INVISIBLE (-6750 2850);
FORCEPROP 1 LAST COMMENT_BODY TRUE
J 2
(-6430 2705);
DISPLAY 0.872340 (-6430 2705);
PAINT GREEN (-6430 2705);
DISPLAY INVISIBLE (-6430 2705);
FORCEPROP 1 LAST OFFPAGE TRUE
J 2
(-6800 2675);
DISPLAY 0.872340 (-6800 2675);
PAINT GREEN (-6800 2675);
DISPLAY INVISIBLE (-6800 2675);
FORCEPROP 2 LAST CDS_LIB standard
J 0
(-6475 2800);
DISPLAY INVISIBLE (-6475 2800);
FORCEADD OFFPAGE..1
(-6475 2700);
FORCEPROP 2 LAST $XR0 94 
J 0
(-6726 2700);
DISPLAY 0.638298 (-6726 2700);
PAINT MONO (-6726 2700);
FORCEPROP 2 LAST PATH I309
J 0
(-6725 2750);
DISPLAY 1.021277 (-6725 2750);
DISPLAY INVISIBLE (-6725 2750);
FORCEPROP 1 LAST COMMENT_BODY TRUE
J 0
(-6350 2600);
DISPLAY 0.872340 (-6350 2600);
PAINT GREEN (-6350 2600);
DISPLAY INVISIBLE (-6350 2600);
FORCEPROP 1 LAST OFFPAGE TRUE
J 0
(-6150 2575);
DISPLAY 0.872340 (-6150 2575);
PAINT GREEN (-6150 2575);
DISPLAY INVISIBLE (-6150 2575);
FORCEPROP 2 LAST CDS_LIB standard
J 0
(-6475 2700);
DISPLAY INVISIBLE (-6475 2700);
FORCEADD OFFPAGE..2
R 2
(-6475 2500);
FORCEPROP 2 LAST $XR0 94 
J 0
(-6729 2500);
DISPLAY 0.638298 (-6729 2500);
PAINT MONO (-6729 2500);
FORCEPROP 2 LAST PATH I310
J 0
(-6750 2550);
DISPLAY 1.021277 (-6750 2550);
DISPLAY INVISIBLE (-6750 2550);
FORCEPROP 1 LAST COMMENT_BODY TRUE
J 2
(-6430 2405);
DISPLAY 0.872340 (-6430 2405);
PAINT GREEN (-6430 2405);
DISPLAY INVISIBLE (-6430 2405);
FORCEPROP 1 LAST OFFPAGE TRUE
J 2
(-6800 2375);
DISPLAY 0.872340 (-6800 2375);
PAINT GREEN (-6800 2375);
DISPLAY INVISIBLE (-6800 2375);
FORCEPROP 2 LAST CDS_LIB standard
J 0
(-6475 2500);
DISPLAY INVISIBLE (-6475 2500);
FORCEADD OFFPAGE..2
R 2
(-6475 2450);
FORCEPROP 2 LAST $XR0 94 
J 0
(-6729 2450);
DISPLAY 0.638298 (-6729 2450);
PAINT MONO (-6729 2450);
FORCEPROP 2 LAST PATH I311
J 0
(-6750 2500);
DISPLAY 1.021277 (-6750 2500);
DISPLAY INVISIBLE (-6750 2500);
FORCEPROP 1 LAST COMMENT_BODY TRUE
J 2
(-6430 2355);
DISPLAY 0.872340 (-6430 2355);
PAINT GREEN (-6430 2355);
DISPLAY INVISIBLE (-6430 2355);
FORCEPROP 1 LAST OFFPAGE TRUE
J 2
(-6800 2325);
DISPLAY 0.872340 (-6800 2325);
PAINT GREEN (-6800 2325);
DISPLAY INVISIBLE (-6800 2325);
FORCEPROP 2 LAST CDS_LIB standard
J 0
(-6475 2450);
DISPLAY INVISIBLE (-6475 2450);
FORCEADD OFFPAGE..1
(-6475 2350);
FORCEPROP 2 LAST $XR0 94 
J 0
(-6726 2350);
DISPLAY 0.638298 (-6726 2350);
PAINT MONO (-6726 2350);
FORCEPROP 2 LAST PATH I312
J 0
(-6725 2400);
DISPLAY 1.021277 (-6725 2400);
DISPLAY INVISIBLE (-6725 2400);
FORCEPROP 1 LAST COMMENT_BODY TRUE
J 0
(-6350 2250);
DISPLAY 0.872340 (-6350 2250);
PAINT GREEN (-6350 2250);
DISPLAY INVISIBLE (-6350 2250);
FORCEPROP 1 LAST OFFPAGE TRUE
J 0
(-6150 2225);
DISPLAY 0.872340 (-6150 2225);
PAINT GREEN (-6150 2225);
DISPLAY INVISIBLE (-6150 2225);
FORCEPROP 2 LAST CDS_LIB standard
J 0
(-6475 2350);
DISPLAY INVISIBLE (-6475 2350);
FORCEADD OFFPAGE..5
(-6475 2250);
FORCEPROP 2 LAST $XR0 94 
J 0
(-6729 2250);
DISPLAY 0.638298 (-6729 2250);
PAINT MONO (-6729 2250);
FORCEPROP 2 LAST PATH I313
J 0
(-6750 2300);
DISPLAY 1.021277 (-6750 2300);
DISPLAY INVISIBLE (-6750 2300);
FORCEPROP 1 LAST COMMENT_BODY TRUE
J 0
(-6375 2175);
DISPLAY 0.872340 (-6375 2175);
PAINT GREEN (-6375 2175);
DISPLAY INVISIBLE (-6375 2175);
FORCEPROP 1 LAST OFFPAGE TRUE
J 0
(-6150 2125);
DISPLAY 0.872340 (-6150 2125);
PAINT GREEN (-6150 2125);
DISPLAY INVISIBLE (-6150 2125);
FORCEPROP 2 LAST CDS_LIB standard
J 0
(-6475 2250);
DISPLAY INVISIBLE (-6475 2250);
FORCEADD Q_RES..1
(-6800 2150);
FORCEPROP 1 LAST LOCATION R384
J 0
(-7125 2150);
DISPLAY 0.489362 (-7125 2150);
PAINT SKYBLUE (-7125 2150);
FORCEPROP 0 LAST $SEC 1
J 0
(-6975 2200);
DISPLAY 0.680851 (-6975 2200);
PAINT MONO (-6975 2200);
DISPLAY INVISIBLE (-6975 2200);
FORCEPROP 0 LAST CDS_SEC 1
J 0
(-6975 2200);
DISPLAY 1.021277 (-6975 2200);
DISPLAY INVISIBLE (-6975 2200);
FORCEPROP 1 LASTPIN (-6900 2150) $PN 1
J 0
(-6888 2162);
DISPLAY 0.489362 (-6888 2162);
PAINT MONO (-6888 2162);
FORCEPROP 1 LASTPIN (-6700 2150) $PN 2
J 0
(-6738 2162);
DISPLAY 0.489362 (-6738 2162);
PAINT MONO (-6738 2162);
FORCEPROP 1 LAST TOLERANCE 1%
J 0
(-6525 2150);
DISPLAY 0.489362 (-6525 2150);
PAINT SKYBLUE (-6525 2150);
FORCEPROP 1 LAST VALUE 15   
J 2
(-6475 2150);
DISPLAY 0.489362 (-6475 2150);
PAINT SKYBLUE (-6475 2150);
FORCEPROP 1 LAST PART_NUMBER CS01502FB11
J 0
(-6700 2125);
DISPLAY 0.489362 (-6700 2125);
PAINT SKYBLUE (-6700 2125);
FORCEPROP 1 LAST PACK_TYPE 0402LF
J 0
(-7125 2125);
DISPLAY 0.489362 (-7125 2125);
PAINT SKYBLUE (-7125 2125);
FORCEPROP 2 LAST CDS_LIB pure_quanta
J 0
(-6800 2150);
DISPLAY INVISIBLE (-6800 2150);
FORCEPROP 1 LAST PATH I314
J 0
(-6850 2300);
DISPLAY 0.978723 (-6850 2300);
PAINT WHITE (-6850 2300);
DISPLAY INVISIBLE (-6850 2300);
FORCEPROP 1 LAST WATTAGE 1/16W
J 2
(-6575 2275);
DISPLAY 0.638298 (-6575 2275);
PAINT SKYBLUE (-6575 2275);
DISPLAY INVISIBLE (-6575 2275);
FORCEPROP 1 LAST MATERIAL CHIP
J 0
(-6925 2275);
DISPLAY 0.638298 (-6925 2275);
PAINT SKYBLUE (-6925 2275);
DISPLAY INVISIBLE (-6925 2275);
FORCEADD OFFPAGE..1
(-7675 2150);
FORCEPROP 2 LAST $XR0 94 
J 0
(-7926 2150);
DISPLAY 0.638298 (-7926 2150);
PAINT MONO (-7926 2150);
FORCEPROP 2 LAST PATH I315
J 0
(-7950 2200);
DISPLAY 1.021277 (-7950 2200);
DISPLAY INVISIBLE (-7950 2200);
FORCEPROP 1 LAST COMMENT_BODY TRUE
J 0
(-7550 2050);
DISPLAY 0.872340 (-7550 2050);
PAINT GREEN (-7550 2050);
DISPLAY INVISIBLE (-7550 2050);
FORCEPROP 1 LAST OFFPAGE TRUE
J 0
(-7350 2025);
DISPLAY 0.872340 (-7350 2025);
PAINT GREEN (-7350 2025);
DISPLAY INVISIBLE (-7350 2025);
FORCEPROP 2 LAST CDS_LIB mstr_standard
J 0
(-7675 2150);
DISPLAY INVISIBLE (-7675 2150);
FORCEADD OFFPAGE..5
(-6475 2050);
FORCEPROP 2 LAST $XR0 94 
J 0
(-6729 2050);
DISPLAY 0.638298 (-6729 2050);
PAINT MONO (-6729 2050);
FORCEPROP 2 LAST PATH I316
J 0
(-6750 2100);
DISPLAY 1.021277 (-6750 2100);
DISPLAY INVISIBLE (-6750 2100);
FORCEPROP 1 LAST COMMENT_BODY TRUE
J 0
(-6375 1975);
DISPLAY 0.872340 (-6375 1975);
PAINT GREEN (-6375 1975);
DISPLAY INVISIBLE (-6375 1975);
FORCEPROP 1 LAST OFFPAGE TRUE
J 0
(-6150 1925);
DISPLAY 0.872340 (-6150 1925);
PAINT GREEN (-6150 1925);
DISPLAY INVISIBLE (-6150 1925);
FORCEPROP 2 LAST CDS_LIB standard
J 0
(-6475 2050);
DISPLAY INVISIBLE (-6475 2050);
FORCEADD QUANTA_TITLE_BLOCK_C..1
(0 0);
FORCEPROP 0 LAST CDS_CON_LAST_MODIFIED Fri Mar 11 14:52:16 2022
J 0
(-1885 15);
DISPLAY INVISIBLE (-1885 15);
FORCEPROP 1 LAST CUSTOM_TXT_CDS <CON_LAST_MODIFIED>
J 0
(-1885 15);
DISPLAY 0.978723 (-1885 15);
FORCEPROP 2 LAST CUSTOM_TXT_CDS <XR_PAGE_TITLE>
J 0
(-7890 5250);
DISPLAY 0.638298 (-7890 5250);
PAINT PINK (-7890 5250);
DISPLAY INVISIBLE (-7890 5250);
FORCEPROP 1 LAST CUSTOM_TXT_CDS <NAME_2>
J 0
(-3175 50);
FORCEPROP 1 LAST CUSTOM_TXT_CDS <NAME_1>
J 0
(-3175 175);
FORCEPROP 1 LAST CUSTOM_TXT_CDS <Q_NUMBER>
J 0
(-1403 103);
DISPLAY 1.212766 (-1403 103);
FORCEPROP 1 LAST CUSTOM_TXT_CDS <Q_PROJ>
J 0
(-2382 102);
DISPLAY 1.212766 (-2382 102);
FORCEPROP 1 LAST CUSTOM_TXT_CDS <Q_REV>
J 0
(-184 103);
DISPLAY 1.212766 (-184 103);
FORCEPROP 1 LAST CUSTOM_TXT_CDS <CON_PAGE_NUM> OF <CON_TOTAL_PAGES>
J 0
(-446 18);
DISPLAY 0.978723 (-446 18);
FORCEPROP 1 LAST Q_DEPT BU9
J 1
(-3763 49);
DISPLAY 1.957447 (-3763 49);
PAINT GREEN (-3763 49);
FORCEPROP 1 LAST Q_TITLE CPU0 DDR CHJ
J 0
(-9300 50);
DISPLAY 2.446809 (-9300 50);
PAINT GREEN (-9300 50);
FORCEPROP 1 LAST CDS_LMAN_SYM_OUTLINE -9475,6775,100,-125
J 0
(0 0);
DISPLAY 0.468085 (0 0);
PAINT GREEN (0 0);
DISPLAY INVISIBLE (0 0);
FORCEPROP 2 LAST CDS_LIB pure_quanta
J 0
(0 0);
DISPLAY INVISIBLE (0 0);
FORCEPROP 2 LAST PAGE_BORDER TRUE
J 0
(-7890 5250);
DISPLAY 0.638298 (-7890 5250);
PAINT PINK (-7890 5250);
DISPLAY INVISIBLE (-7890 5250);
FORCEPROP 1 LAST COMMENT_BODY TRUE
J 0
(12 -13);
DISPLAY 0.978723 (12 -13);
PAINT GREEN (12 -13);
DISPLAY INVISIBLE (12 -13);
FORCEPROP 2 LAST CDS_XR_PAGE_TITLE CR-19 : @T6G_MB_LIB.T6G(SCH_1):PAGE19
J 0
(-7890 5250);
DISPLAY 0.638298 (-7890 5250);
PAINT PINK (-7890 5250);
DISPLAY INVISIBLE (-7890 5250);
FORCEADD CAD_NOTE..1
(-7650 2475);
FORCEPROP 0 LAST L1 R1949 PLACE CLOSE TO CPU < 25MM
J 0
(-7800 2350);
DISPLAY 0.617021 (-7800 2350);
PAINT WHITE (-7800 2350);
FORCEPROP 2 LAST CDS_LIB pure_quanta_power
J 0
(-7650 2475);
DISPLAY INVISIBLE (-7650 2475);
FORCEPROP 1 LAST COMMENT_BODY TRUE
J 0
(-7625 2575);
DISPLAY 0.574468 (-7625 2575);
PAINT WHITE (-7625 2575);
DISPLAY INVISIBLE (-7625 2575);
WIRE 17 -1 (-3200 5275)(-3200 5225);
WIRE 17 -1 (-3200 5325)(-3200 5275);
WIRE 17 -1 (-3200 5125)(-3200 5225);
WIRE 17 -1 (-3200 5075)(-3200 5125);
WIRE 17 -1 (-3200 5375)(-3200 5325);
WIRE 17 -1 (-3200 5425)(-3200 5375);
WIRE 17 -1 (-3200 5025)(-3200 5075);
WIRE 17 -1 (-3200 4975)(-3200 5025);
WIRE 17 -1 (-3200 5475)(-3200 5425);
WIRE 17 -1 (-3200 5525)(-3200 5475);
WIRE 17 -1 (-3200 4975)(-3200 4925);
WIRE 17 -1 (-3200 4925)(-3200 4875);
WIRE 17 -1 (-3200 5575)(-3200 5525);
WIRE 17 -1 (-3200 5675)(-3200 5575);
WIRE 17 -1 (-3200 4875)(-3200 4825);
WIRE 17 -1 (-3200 4825)(-3200 4775);
WIRE 17 -1 (-3200 5725)(-3200 5675);
WIRE 17 -1 (-3200 5775)(-3200 5725);
WIRE 17 -1 (-3200 4775)(-3200 4675);
WIRE 17 -1 (-3200 4675)(-3200 4625);
WIRE 17 -1 (-3200 5825)(-3200 5775);
WIRE 17 -1 (-3200 5875)(-3200 5825);
WIRE 17 -1 (-3200 4625)(-3200 4575);
WIRE 17 -1 (-3200 4575)(-3200 4525);
WIRE 17 -1 (-3200 5925)(-3200 5875);
WIRE 17 -1 (-3200 5975)(-3200 5925);
WIRE 17 -1 (-3200 4475)(-3200 4525);
WIRE 17 -1 (-3200 4425)(-3200 4475);
WIRE 17 -1 (-3200 6025)(-3200 5975);
WIRE 17 -1 (-3200 6025)(-2575 6025);
FORCEPROP 2 LAST SIG_NAME M_J_CPU0_SA_DQ<31:0>
J 2
(-2635 6035);
DISPLAY 0.489362 (-2635 6035);
WIRE 17 -1 (-3200 4125)(-3200 4075);
WIRE 17 -1 (-3200 4175)(-3200 4125);
WIRE 17 -1 (-3200 4075)(-3200 4025);
WIRE 17 -1 (-3200 4025)(-3200 3975);
WIRE 17 -1 (-3200 4225)(-3200 4175);
WIRE 17 -1 (-3200 4225)(-2575 4225);
FORCEPROP 2 LAST SIG_NAME M_J_CPU0_SB_DQ<31:0>
J 2
(-2635 4235);
DISPLAY 0.489362 (-2635 4235);
WIRE 17 -1 (-3200 4325)(-3200 4375);
WIRE 17 -1 (-3200 4375)(-3200 4425);
WIRE 17 -1 (-3200 3125)(-3200 3075);
WIRE 17 -1 (-3200 3175)(-3200 3125);
WIRE 17 -1 (-3200 3075)(-3200 3025);
WIRE 17 -1 (-3200 3025)(-3200 2975);
WIRE 17 -1 (-3200 3175)(-3200 3225);
WIRE 17 -1 (-3200 3225)(-3200 3275);
WIRE 17 -1 (-3200 2975)(-3200 2875);
WIRE 17 -1 (-3200 2875)(-3200 2825);
WIRE 17 -1 (-3200 3275)(-3200 3325);
WIRE 17 -1 (-3200 3325)(-3200 3425);
WIRE 17 -1 (-3200 2825)(-3200 2775);
WIRE 17 -1 (-3200 2775)(-3200 2725);
WIRE 17 -1 (-3200 3475)(-3200 3425);
WIRE 17 -1 (-3200 3525)(-3200 3475);
WIRE 17 -1 (-3200 2675)(-3200 2725);
WIRE 17 -1 (-3200 2625)(-3200 2675);
WIRE 17 -1 (-3200 3575)(-3200 3525);
WIRE 17 -1 (-3200 3625)(-3200 3575);
WIRE 17 -1 (-3200 2575)(-3200 2625);
WIRE 17 -1 (-3200 2525)(-3200 2575);
WIRE 17 -1 (-3200 3675)(-3200 3625);
WIRE 17 -1 (-3200 3725)(-3200 3675);
WIRE 17 -1 (-3200 3775)(-3200 3725);
WIRE 17 -1 (-3200 3875)(-3200 3775);
WIRE 17 -1 (-3200 3925)(-3200 3875);
WIRE 17 -1 (-3200 3975)(-3200 3925);
WIRE 17 -1 (-3200 2075)(-3200 2125);
WIRE 17 -1 (-3200 2125)(-3200 2175);
WIRE 17 -1 (-3200 2175)(-3200 2225);
WIRE 17 -1 (-3200 2225)(-3200 2275);
WIRE 17 -1 (-3200 2325)(-3200 2275);
WIRE 17 -1 (-3200 2325)(-3200 2375);
WIRE 17 -1 (-3200 2425)(-3200 2375);
WIRE 17 -1 (-3200 2425)(-3200 2450);
WIRE 17 -1 (-3200 2450)(-2700 2450);
FORCEPROP 2 LAST SIG_NAME M_J_CPU0_SA_CB<7:0>
J 2
(-2700 2460);
DISPLAY 0.489362 (-2700 2460);
WIRE 17 -1 (-3200 1625)(-3200 1675);
WIRE 17 -1 (-3200 1675)(-3200 1725);
WIRE 17 -1 (-3200 1725)(-3200 1775);
WIRE 17 -1 (-3200 1775)(-3200 1825);
WIRE 17 -1 (-3200 1875)(-3200 1825);
WIRE 17 -1 (-3200 1875)(-3200 1925);
WIRE 17 -1 (-3200 1975)(-3200 1925);
WIRE 17 -1 (-3200 1975)(-3200 2000);
WIRE 17 -1 (-3200 2000)(-2700 2000);
FORCEPROP 2 LAST SIG_NAME M_J_CPU0_SB_CB<7:0>
J 2
(-2700 2010);
DISPLAY 0.489362 (-2700 2010);
WIRE 17 -1 (-5725 5725)(-5725 5625);
WIRE 17 -1 (-5725 5825)(-5725 5725);
WIRE 17 -1 (-5725 5525)(-5725 5625);
WIRE 17 -1 (-5725 5425)(-5725 5525);
WIRE 17 -1 (-5725 5925)(-5725 5825);
WIRE 17 -1 (-5725 6025)(-5725 5925);
WIRE 17 -1 (-5725 5325)(-5725 5425);
WIRE 17 -1 (-5725 5325)(-5725 5225);
WIRE 17 -1 (-5725 6025)(-6525 6025);
FORCEPROP 2 LAST SIG_NAME M_J_CPU0_SA_DQS_DP<9:0>
J 2
(-5960 6035);
DISPLAY 0.489362 (-5960 6035);
WIRE 17 -1 (-5725 5225)(-5725 5125);
WIRE 17 -1 (-5925 5275)(-5925 5175);
WIRE 17 -1 (-5925 5275)(-5925 5375);
WIRE 17 -1 (-5925 5175)(-5925 5075);
WIRE 17 -1 (-5925 5375)(-5925 5475);
WIRE 17 -1 (-5925 5475)(-5925 5575);
WIRE 17 -1 (-5925 5675)(-5925 5575);
WIRE 17 -1 (-5925 5775)(-5925 5675);
WIRE 17 -1 (-5925 5875)(-5925 5775);
WIRE 17 -1 (-5925 5975)(-5925 5875);
FORCEPROP 2 LAST SIG_NAME M_J_CPU0_SA_DQS_DN<9:0>
J 2
(-5960 5985);
DISPLAY 0.489362 (-5960 5985);
WIRE 17 -1 (-5725 4675)(-5725 4575);
WIRE 17 -1 (-5725 4775)(-5725 4675);
WIRE 17 -1 (-5725 4475)(-5725 4575);
WIRE 17 -1 (-5725 4375)(-5725 4475);
WIRE 17 -1 (-5725 4875)(-5725 4775);
WIRE 17 -1 (-5725 4975)(-5725 4875);
WIRE 17 -1 (-5725 4275)(-5725 4375);
WIRE 17 -1 (-5725 4275)(-5725 4175);
WIRE 17 -1 (-5725 4975)(-6525 4975);
FORCEPROP 2 LAST SIG_NAME M_J_CPU0_SB_DQS_DP<9:0>
J 2
(-5960 4985);
DISPLAY 0.489362 (-5960 4985);
WIRE 17 -1 (-5725 4175)(-5725 4075);
WIRE 17 -1 (-5925 4225)(-5925 4125);
WIRE 17 -1 (-5925 4225)(-5925 4325);
WIRE 17 -1 (-5925 4125)(-5925 4025);
WIRE 17 -1 (-5925 4325)(-5925 4425);
WIRE 17 -1 (-5925 4425)(-5925 4525);
WIRE 17 -1 (-5925 4625)(-5925 4525);
WIRE 17 -1 (-5925 4725)(-5925 4625);
WIRE 17 -1 (-5925 4825)(-5925 4725);
WIRE 17 -1 (-5925 4925)(-5925 4825);
FORCEPROP 2 LAST SIG_NAME M_J_CPU0_SB_DQS_DN<9:0>
J 2
(-5960 4935);
DISPLAY 0.489362 (-5960 4935);
WIRE 17 -1 (-5925 3175)(-5925 3225);
WIRE 17 -1 (-5925 3225)(-5925 3275);
WIRE 17 -1 (-5925 3275)(-5925 3325);
WIRE 17 -1 (-5925 3325)(-5925 3375);
WIRE 17 -1 (-5925 3375)(-5925 3425);
WIRE 17 -1 (-5925 3425)(-5925 3475);
WIRE 17 -1 (-5925 3475)(-6425 3475);
FORCEPROP 2 LAST SIG_NAME M_J_CPU0_SB_CA<6:0>
J 0
(-6425 3485);
DISPLAY 0.489362 (-6425 3485);
WIRE 17 -1 (-5925 3675)(-5925 3725);
WIRE 17 -1 (-5925 3625)(-5925 3675);
WIRE 17 -1 (-5925 3725)(-5925 3775);
WIRE 17 -1 (-5925 3775)(-5925 3825);
WIRE 17 -1 (-5925 3575)(-5925 3625);
WIRE 17 -1 (-5925 3825)(-5925 3875);
WIRE 17 -1 (-5925 3875)(-6425 3875);
FORCEPROP 2 LAST SIG_NAME M_J_CPU0_SA_CA<6:0>
J 0
(-6425 3885);
DISPLAY 0.489362 (-6425 3885);
WIRE 17 -1 (-5925 5975)(-6525 5975);
WIRE 17 -1 (-5925 4925)(-6525 4925);
WIRE 16 -1 (-7625 2150)(-6900 2150);
FORCEPROP 2 LAST SIG_NAME M_J_CPU0_ALERT_N
J 0
(-7585 2160);
DISPLAY 0.489362 (-7585 2160);
WIRE 16 -1 (-6425 1200)(-5325 1200);
FORCEPROP 2 LAST SIG_NAME TP_M_J_CPU0_SA_TEST39J
J 0
(-6410 1210);
DISPLAY 0.489362 (-6410 1210);
FORCEPROP 2 LASTPROP $XRERR UNIQUE?
J 0
(-6665 1200);
DISPLAY 0.638298 (-6665 1200);
PAINT MONO (-6665 1200);
DISPLAY INVISIBLE (-6665 1200);
WIRE 16 -1 (-6700 2150)(-5325 2150);
FORCEPROP 2 LAST SIG_NAME M_J_CPU0_ALERT_R_N
J 0
(-6410 2160);
DISPLAY 0.489362 (-6410 2160);
FORCEPROP 2 LASTPROP $XRERR UNIQUE?
J 0
(-6650 2160);
DISPLAY 0.638298 (-6650 2160);
PAINT MONO (-6650 2160);
DISPLAY INVISIBLE (-6650 2160);
WIRE 16 -1 (-6425 3000)(-5325 3000);
FORCEPROP 2 LAST SIG_NAME M_J_CPU0_CLK_DP<0>
J 0
(-6425 3010);
DISPLAY 0.489362 (-6425 3010);
WIRE 16 -1 (-6425 2950)(-5325 2950);
FORCEPROP 2 LAST SIG_NAME M_J_CPU0_CLK_DN<0>
J 0
(-6425 2960);
DISPLAY 0.489362 (-6425 2960);
WIRE 16 -1 (-6425 2850)(-5325 2850);
FORCEPROP 2 LAST SIG_NAME M_J_CPU0_SA_CS_N<0>
J 0
(-6425 2860);
DISPLAY 0.489362 (-6425 2860);
WIRE 16 -1 (-6425 2600)(-5325 2600);
FORCEPROP 2 LAST SIG_NAME M_J_CPU0_SA_PAR
J 0
(-6425 2610);
DISPLAY 0.489362 (-6425 2610);
WIRE 16 -1 (-6425 2800)(-5325 2800);
FORCEPROP 2 LAST SIG_NAME M_J_CPU0_SA_CS_N<1>
J 0
(-6425 2810);
DISPLAY 0.489362 (-6425 2810);
WIRE 16 -1 (-6425 2700)(-5325 2700);
FORCEPROP 2 LAST SIG_NAME M_J_CPU0_SA_RSP<0>
J 0
(-6425 2710);
DISPLAY 0.489362 (-6425 2710);
WIRE 16 -1 (-6425 2500)(-5325 2500);
FORCEPROP 2 LAST SIG_NAME M_J_CPU0_SB_CS_N<0>
J 0
(-6425 2510);
DISPLAY 0.489362 (-6425 2510);
WIRE 16 -1 (-6425 2450)(-5325 2450);
FORCEPROP 2 LAST SIG_NAME M_J_CPU0_SB_CS_N<1>
J 0
(-6425 2460);
DISPLAY 0.489362 (-6425 2460);
WIRE 16 -1 (-6425 2350)(-5325 2350);
FORCEPROP 2 LAST SIG_NAME M_J_CPU0_SB_RSP<0>
J 0
(-6425 2360);
DISPLAY 0.489362 (-6425 2360);
WIRE 16 -1 (-6425 2250)(-5325 2250);
FORCEPROP 2 LAST SIG_NAME M_J_CPU0_SB_PAR
J 0
(-6425 2260);
DISPLAY 0.489362 (-6425 2260);
WIRE 16 -1 (-6425 2050)(-5325 2050);
FORCEPROP 2 LAST SIG_NAME M_J_CPU0_RESET_N
J 0
(-6425 2060);
DISPLAY 0.489362 (-6425 2060);
WIRE 16 -1 (-5825 3600)(-5325 3600);
WIRE 16 -1 (-5825 3550)(-5325 3550);
WIRE 16 -1 (-5825 3850)(-5325 3850);
WIRE 16 -1 (-5825 3800)(-5325 3800);
WIRE 16 -1 (-5825 3750)(-5325 3750);
WIRE 16 -1 (-5825 3700)(-5325 3700);
WIRE 16 -1 (-5825 3650)(-5325 3650);
WIRE 16 -1 (-5825 3450)(-5325 3450);
WIRE 16 -1 (-5825 3400)(-5325 3400);
WIRE 16 -1 (-5825 3350)(-5325 3350);
WIRE 16 -1 (-5825 3300)(-5325 3300);
WIRE 16 -1 (-5825 3250)(-5325 3250);
WIRE 16 -1 (-5825 3200)(-5325 3200);
WIRE 16 -1 (-5825 3150)(-5325 3150);
WIRE 16 -1 (-5825 4000)(-5325 4000);
WIRE 16 -1 (-5625 4050)(-5325 4050);
WIRE 16 -1 (-5825 4500)(-5325 4500);
WIRE 16 -1 (-5825 4900)(-5325 4900);
WIRE 16 -1 (-5825 5050)(-5325 5050);
WIRE 16 -1 (-5825 4800)(-5325 4800);
WIRE 16 -1 (-5825 4700)(-5325 4700);
WIRE 16 -1 (-5825 4600)(-5325 4600);
WIRE 16 -1 (-5825 4400)(-5325 4400);
WIRE 16 -1 (-5825 4300)(-5325 4300);
WIRE 16 -1 (-5825 4200)(-5325 4200);
WIRE 16 -1 (-5825 4100)(-5325 4100);
WIRE 16 -1 (-5625 4450)(-5325 4450);
WIRE 16 -1 (-5625 4550)(-5325 4550);
WIRE 16 -1 (-5625 4350)(-5325 4350);
WIRE 16 -1 (-5625 4250)(-5325 4250);
WIRE 16 -1 (-5625 4150)(-5325 4150);
WIRE 16 -1 (-5625 5100)(-5325 5100);
WIRE 16 -1 (-5625 4950)(-5325 4950);
WIRE 16 -1 (-5625 4850)(-5325 4850);
WIRE 16 -1 (-5625 4750)(-5325 4750);
WIRE 16 -1 (-5625 4650)(-5325 4650);
WIRE 16 -1 (-5825 5550)(-5325 5550);
WIRE 16 -1 (-5825 5450)(-5325 5450);
WIRE 16 -1 (-5825 5250)(-5325 5250);
WIRE 16 -1 (-5825 5950)(-5325 5950);
WIRE 16 -1 (-5825 5850)(-5325 5850);
WIRE 16 -1 (-5825 5750)(-5325 5750);
WIRE 16 -1 (-5825 5650)(-5325 5650);
WIRE 16 -1 (-5825 5350)(-5325 5350);
WIRE 16 -1 (-5825 5150)(-5325 5150);
WIRE 16 -1 (-5625 5600)(-5325 5600);
WIRE 16 -1 (-5625 5200)(-5325 5200);
WIRE 16 -1 (-5625 5500)(-5325 5500);
WIRE 16 -1 (-5625 5400)(-5325 5400);
WIRE 16 -1 (-5625 5300)(-5325 5300);
WIRE 16 -1 (-5625 6000)(-5325 6000);
WIRE 16 -1 (-5625 5900)(-5325 5900);
WIRE 16 -1 (-5625 5800)(-5325 5800);
WIRE 16 -1 (-5625 5700)(-5325 5700);
WIRE 16 -1 (-3725 1950)(-3300 1950);
WIRE 16 -1 (-3725 1900)(-3300 1900);
WIRE 16 -1 (-3725 1850)(-3300 1850);
WIRE 16 -1 (-3725 1800)(-3300 1800);
WIRE 16 -1 (-3725 1750)(-3300 1750);
WIRE 16 -1 (-3725 1700)(-3300 1700);
WIRE 16 -1 (-3725 1650)(-3300 1650);
WIRE 16 -1 (-3725 1600)(-3300 1600);
WIRE 16 -1 (-3725 2400)(-3300 2400);
WIRE 16 -1 (-3725 2350)(-3300 2350);
WIRE 16 -1 (-3725 2300)(-3300 2300);
WIRE 16 -1 (-3725 2250)(-3300 2250);
WIRE 16 -1 (-3725 2200)(-3300 2200);
WIRE 16 -1 (-3725 2150)(-3300 2150);
WIRE 16 -1 (-3725 2100)(-3300 2100);
WIRE 16 -1 (-3725 2050)(-3300 2050);
WIRE 16 -1 (-3725 3050)(-3300 3050);
WIRE 16 -1 (-3725 3000)(-3300 3000);
WIRE 16 -1 (-3725 2950)(-3300 2950);
WIRE 16 -1 (-3725 2850)(-3300 2850);
WIRE 16 -1 (-3725 2800)(-3300 2800);
WIRE 16 -1 (-3725 2750)(-3300 2750);
WIRE 16 -1 (-3725 2700)(-3300 2700);
WIRE 16 -1 (-3725 2650)(-3300 2650);
WIRE 16 -1 (-3725 2600)(-3300 2600);
WIRE 16 -1 (-3725 2550)(-3300 2550);
WIRE 16 -1 (-3725 2500)(-3300 2500);
WIRE 16 -1 (-3725 3850)(-3300 3850);
WIRE 16 -1 (-3725 3900)(-3300 3900);
WIRE 16 -1 (-3725 3950)(-3300 3950);
WIRE 16 -1 (-3725 4050)(-3300 4050);
WIRE 16 -1 (-3725 4000)(-3300 4000);
WIRE 16 -1 (-3725 3750)(-3300 3750);
WIRE 16 -1 (-3725 3700)(-3300 3700);
WIRE 16 -1 (-3725 3650)(-3300 3650);
WIRE 16 -1 (-3725 3600)(-3300 3600);
WIRE 16 -1 (-3725 3550)(-3300 3550);
WIRE 16 -1 (-3725 3500)(-3300 3500);
WIRE 16 -1 (-3725 3450)(-3300 3450);
WIRE 16 -1 (-3725 3400)(-3300 3400);
WIRE 16 -1 (-3725 3300)(-3300 3300);
WIRE 16 -1 (-3725 3250)(-3300 3250);
WIRE 16 -1 (-3725 3200)(-3300 3200);
WIRE 16 -1 (-3725 3150)(-3300 3150);
WIRE 16 -1 (-3725 3100)(-3300 3100);
WIRE 16 -1 (-3725 4300)(-3300 4300);
WIRE 16 -1 (-3725 4200)(-3300 4200);
WIRE 16 -1 (-3725 4800)(-3300 4800);
WIRE 16 -1 (-3725 5100)(-3300 5100);
WIRE 16 -1 (-3725 5050)(-3300 5050);
WIRE 16 -1 (-3725 5000)(-3300 5000);
WIRE 16 -1 (-3725 4950)(-3300 4950);
WIRE 16 -1 (-3725 4900)(-3300 4900);
WIRE 16 -1 (-3725 4850)(-3300 4850);
WIRE 16 -1 (-3725 4750)(-3300 4750);
WIRE 16 -1 (-3725 4650)(-3300 4650);
WIRE 16 -1 (-3725 4600)(-3300 4600);
WIRE 16 -1 (-3725 4550)(-3300 4550);
WIRE 16 -1 (-3725 4500)(-3300 4500);
WIRE 16 -1 (-3725 4450)(-3300 4450);
WIRE 16 -1 (-3725 4400)(-3300 4400);
WIRE 16 -1 (-3725 4350)(-3300 4350);
WIRE 16 -1 (-3725 4150)(-3300 4150);
WIRE 16 -1 (-3725 4100)(-3300 4100);
WIRE 16 -1 (-3725 6000)(-3300 6000);
WIRE 16 -1 (-3725 5950)(-3300 5950);
WIRE 16 -1 (-3725 5900)(-3300 5900);
WIRE 16 -1 (-3725 5850)(-3300 5850);
WIRE 16 -1 (-3725 5800)(-3300 5800);
WIRE 16 -1 (-3725 5750)(-3300 5750);
WIRE 16 -1 (-3725 5700)(-3300 5700);
WIRE 16 -1 (-3725 5650)(-3300 5650);
WIRE 16 -1 (-3725 5550)(-3300 5550);
WIRE 16 -1 (-3725 5500)(-3300 5500);
WIRE 16 -1 (-3725 5450)(-3300 5450);
WIRE 16 -1 (-3725 5400)(-3300 5400);
WIRE 16 -1 (-3725 5350)(-3300 5350);
WIRE 16 -1 (-3725 5300)(-3300 5300);
WIRE 16 -1 (-3725 5250)(-3300 5250);
WIRE 16 -1 (-3725 5200)(-3300 5200);
QUIT
